(kicad_sch (version 20211123) (generator eeschema)

  (paper "A3")

  (title_block
    (title "SA800U (Snapdragon 845) Baseboard")
    (date "2023-10-19")
    (rev "1.0.3")
    (company "Antmicro Ltd.")
    (comment 1 "www.antmicro.com")
  )

  (junction (at 349.25 213.995) (diameter 0) (color 0 0 0 0)
  )
  (junction (at 349.25 223.52) (diameter 0) (color 0 0 0 0)
  )
  (junction (at 349.25 213.868) (diameter 0) (color 0 0 0 0)
  )

  (wire (pts (xy 349.25 223.52) (xy 349.25 224.79))
    (stroke (width 0) (type default) (color 0 0 0 0))
  )
  (wire (pts (xy 359.41 223.52) (xy 363.22 223.52))
    (stroke (width 0) (type default) (color 0 0 0 0))
  )
  (wire (pts (xy 349.25 236.22) (xy 349.25 237.49))
    (stroke (width 0) (type default) (color 0 0 0 0))
  )
  (wire (pts (xy 354.33 204.978) (xy 349.25 204.978))
    (stroke (width 0) (type default) (color 0 0 0 0))
  )
  (wire (pts (xy 354.33 213.868) (xy 349.25 213.868))
    (stroke (width 0) (type default) (color 0 0 0 0))
  )
  (wire (pts (xy 359.41 213.868) (xy 363.22 213.868))
    (stroke (width 0) (type default) (color 0 0 0 0))
  )
  (wire (pts (xy 349.25 236.22) (xy 354.33 236.22))
    (stroke (width 0) (type default) (color 0 0 0 0))
  )
  (wire (pts (xy 349.25 204.978) (xy 349.25 213.868))
    (stroke (width 0) (type default) (color 0 0 0 0))
  )
  (wire (pts (xy 359.41 236.22) (xy 363.22 236.22))
    (stroke (width 0) (type default) (color 0 0 0 0))
  )
  (wire (pts (xy 359.41 204.978) (xy 363.22 204.978))
    (stroke (width 0) (type default) (color 0 0 0 0))
  )
  (wire (pts (xy 349.25 213.995) (xy 349.25 223.52))
    (stroke (width 0) (type default) (color 0 0 0 0))
  )
  (wire (pts (xy 349.25 223.52) (xy 354.33 223.52))
    (stroke (width 0) (type default) (color 0 0 0 0))
  )
  (wire (pts (xy 349.25 213.868) (xy 349.25 213.995))
    (stroke (width 0) (type default) (color 0 0 0 0))
  )

  (symbol (lib_name "Spacer_H6mm_9774060151_1") (lib_id "sa800u-baseboard-hw:Spacer_H6mm_9774060151") (at 363.22 223.52 0) (unit 1)
    (in_bom yes) (on_board yes) (fields_autoplaced)
    (property "Reference" "SP3" (id 0) (at 372.11 222.25 0)
      (effects (font (size 1.524 1.524)) (justify left))
    )
    (property "Value" "Spacer_H6mm_9774060151" (id 1) (at 372.11 226.06 0)
      (effects (font (size 1.524 1.524)) (justify left))
    )
    (property "Footprint" "sa800u-baseboard-hw-footprints:Spacer_SMD_M2.5_H6mm_Wurth_9774060151" (id 2) (at 363.22 223.52 0)
      (effects (font (size 1.524 1.524)) hide)
    )
    (property "Datasheet" "https://www.we-online.com/catalog/datasheet/9774060151.pdf" (id 3) (at 363.22 223.52 0)
      (effects (font (size 1.524 1.524)) hide)
    )
    (property "Manufacturer" "Würth Elektronik" (id 4) (at 363.22 223.52 0)
      (effects (font (size 1.27 1.27)) hide)
    )
    (property "MPN" "9774060151" (id 5) (at 363.22 223.52 0)
      (effects (font (size 1.27 1.27)) hide)
    )
    (property "Author" "Antmicro" (id 6) (at 386.08 241.3 0)
      (effects (font (size 1.27 1.27) (thickness 0.15)) (justify left bottom) hide)
    )
    (property "License" "Apache-2.0" (id 7) (at 386.08 243.84 0)
      (effects (font (size 1.27 1.27) (thickness 0.15)) (justify left bottom) hide)
    )
    (pin "1")
  )

  (symbol (lib_name "Spacer_H6mm_9774060151_3") (lib_id "sa800u-baseboard-hw:Spacer_H6mm_9774060151") (at 363.22 236.22 0) (unit 1)
    (in_bom yes) (on_board yes) (fields_autoplaced)
    (property "Reference" "SP4" (id 0) (at 372.11 234.95 0)
      (effects (font (size 1.524 1.524)) (justify left))
    )
    (property "Value" "Spacer_H6mm_9774060151" (id 1) (at 372.11 238.76 0)
      (effects (font (size 1.524 1.524)) (justify left))
    )
    (property "Footprint" "sa800u-baseboard-hw-footprints:Spacer_SMD_M2.5_H6mm_Wurth_9774060151" (id 2) (at 363.22 236.22 0)
      (effects (font (size 1.524 1.524)) hide)
    )
    (property "Datasheet" "https://www.we-online.com/catalog/datasheet/9774060151.pdf" (id 3) (at 363.22 236.22 0)
      (effects (font (size 1.524 1.524)) hide)
    )
    (property "Manufacturer" "Würth Elektronik" (id 4) (at 363.22 236.22 0)
      (effects (font (size 1.27 1.27)) hide)
    )
    (property "MPN" "9774060151" (id 5) (at 363.22 236.22 0)
      (effects (font (size 1.27 1.27)) hide)
    )
    (property "Author" "Antmicro" (id 6) (at 386.08 254 0)
      (effects (font (size 1.27 1.27) (thickness 0.15)) (justify left bottom) hide)
    )
    (property "License" "Apache-2.0" (id 7) (at 386.08 256.54 0)
      (effects (font (size 1.27 1.27) (thickness 0.15)) (justify left bottom) hide)
    )
    (pin "1")
  )

  (symbol (lib_id "sa800u-baseboard-hw:Spacer_H6mm_9774060151") (at 363.22 213.868 0) (unit 1)
    (in_bom yes) (on_board yes) (fields_autoplaced)
    (property "Reference" "SP2" (id 0) (at 372.11 212.598 0)
      (effects (font (size 1.524 1.524)) (justify left))
    )
    (property "Value" "Spacer_H6mm_9774060151" (id 1) (at 372.11 216.408 0)
      (effects (font (size 1.524 1.524)) (justify left))
    )
    (property "Footprint" "sa800u-baseboard-hw-footprints:Spacer_SMD_M2.5_H6mm_Wurth_9774060151" (id 2) (at 363.22 213.868 0)
      (effects (font (size 1.524 1.524)) hide)
    )
    (property "Datasheet" "https://www.we-online.com/catalog/datasheet/9774060151.pdf" (id 3) (at 363.22 213.868 0)
      (effects (font (size 1.524 1.524)) hide)
    )
    (property "Manufacturer" "Würth Elektronik" (id 4) (at 363.22 213.868 0)
      (effects (font (size 1.27 1.27)) hide)
    )
    (property "MPN" "9774060151" (id 5) (at 363.22 213.868 0)
      (effects (font (size 1.27 1.27)) hide)
    )
    (property "Author" "Antmicro" (id 6) (at 386.08 231.648 0)
      (effects (font (size 1.27 1.27) (thickness 0.15)) (justify left bottom) hide)
    )
    (property "License" "Apache-2.0" (id 7) (at 386.08 234.188 0)
      (effects (font (size 1.27 1.27) (thickness 0.15)) (justify left bottom) hide)
    )
    (pin "1")
  )

  (symbol (lib_name "Spacer_H6mm_9774060151_2") (lib_id "sa800u-baseboard-hw:Spacer_H6mm_9774060151") (at 363.22 204.978 0) (unit 1)
    (in_bom yes) (on_board yes) (fields_autoplaced)
    (property "Reference" "SP1" (id 0) (at 372.11 203.708 0)
      (effects (font (size 1.524 1.524)) (justify left))
    )
    (property "Value" "Spacer_H6mm_9774060151" (id 1) (at 372.11 207.518 0)
      (effects (font (size 1.524 1.524)) (justify left))
    )
    (property "Footprint" "sa800u-baseboard-hw-footprints:Spacer_SMD_M2.5_H6mm_Wurth_9774060151" (id 2) (at 363.22 204.978 0)
      (effects (font (size 1.524 1.524)) hide)
    )
    (property "Datasheet" "https://www.we-online.com/catalog/datasheet/9774060151.pdf" (id 3) (at 363.22 204.978 0)
      (effects (font (size 1.524 1.524)) hide)
    )
    (property "Manufacturer" "Würth Elektronik" (id 4) (at 363.22 204.978 0)
      (effects (font (size 1.27 1.27)) hide)
    )
    (property "MPN" "9774060151" (id 5) (at 363.22 204.978 0)
      (effects (font (size 1.27 1.27)) hide)
    )
    (property "Author" "Antmicro" (id 6) (at 386.08 222.758 0)
      (effects (font (size 1.27 1.27) (thickness 0.15)) (justify left bottom) hide)
    )
    (property "License" "Apache-2.0" (id 7) (at 386.08 225.298 0)
      (effects (font (size 1.27 1.27) (thickness 0.15)) (justify left bottom) hide)
    )
    (pin "1")
  )

  (symbol (lib_id "sa800u-baseboard-hw:R_0R_0402") (at 354.33 223.52 0) (unit 1)
    (in_bom yes) (on_board yes)
    (property "Reference" "R3" (id 0) (at 353.314 222.377 0)
      (effects (font (size 1.524 1.524)))
    )
    (property "Value" "R_0R_0402" (id 1) (at 354.33 227.33 0)
      (effects (font (size 1.524 1.524)) hide)
    )
    (property "Footprint" "sa800u-baseboard-hw-footprints:R_0402_1005Metric" (id 2) (at 359.41 218.44 0)
      (effects (font (size 1.524 1.524)) (justify left) hide)
    )
    (property "Datasheet" "https://industrial.panasonic.com/cdbs/www-data/pdf/RDA0000/AOA0000C301.pdf" (id 3) (at 354.33 223.52 0)
      (effects (font (size 1.27 1.27)) hide)
    )
    (property "Manufacturer" "Panasonic" (id 4) (at 359.41 213.36 0)
      (effects (font (size 1.524 1.524)) (justify left) hide)
    )
    (property "MPN" "ERJ2GE0R00X" (id 5) (at 359.41 215.9 0)
      (effects (font (size 1.524 1.524)) (justify left) hide)
    )
    (property "Val" "0R" (id 6) (at 360.172 222.504 0))
    (property "DNP" "DNP" (id 7) (at 356.87 223.52 0))
    (property "License" "Apache-2.0" (id 8) (at 374.65 248.92 0)
      (effects (font (size 1.27 1.27) (thickness 0.15)) (justify left bottom) hide)
    )
    (property "Author" "Antmicro" (id 9) (at 374.65 251.46 0)
      (effects (font (size 1.27 1.27) (thickness 0.15)) (justify left bottom) hide)
    )
    (property "Tolerance" "~" (id 10) (at 374.65 233.68 0)
      (effects (font (size 1.27 1.27)) (justify left bottom) hide)
    )
    (property "Current" "1A" (id 11) (at 374.65 254 0)
      (effects (font (size 1.27 1.27) (thickness 0.15)) (justify left bottom) hide)
    )
    (pin "1")
    (pin "2")
  )

  (symbol (lib_id "sa800u-baseboard-hw:GND") (at 349.25 224.79 0) (unit 1)
    (in_bom yes) (on_board yes)
    (property "Reference" "#PWR01" (id 0) (at 349.25 231.14 0)
      (effects (font (size 1.27 1.27)) hide)
    )
    (property "Value" "GND" (id 1) (at 349.377 229.1842 0))
    (property "Footprint" "" (id 2) (at 349.25 224.79 0)
      (effects (font (size 1.27 1.27)) hide)
    )
    (property "Datasheet" "" (id 3) (at 349.25 224.79 0)
      (effects (font (size 1.27 1.27)) hide)
    )
    (property "Author" "Antmicro" (id 4) (at 358.14 232.41 0)
      (effects (font (size 1.27 1.27) (thickness 0.15)) (justify left bottom) hide)
    )
    (property "License" "Apache-2.0" (id 5) (at 358.14 234.95 0)
      (effects (font (size 1.27 1.27) (thickness 0.15)) (justify left bottom) hide)
    )
    (pin "1")
  )

  (symbol (lib_id "sa800u-baseboard-hw:R_0R_0402") (at 354.33 236.22 0) (unit 1)
    (in_bom yes) (on_board yes)
    (property "Reference" "R4" (id 0) (at 353.314 235.077 0)
      (effects (font (size 1.524 1.524)))
    )
    (property "Value" "R_0R_0402" (id 1) (at 354.33 240.03 0)
      (effects (font (size 1.524 1.524)) hide)
    )
    (property "Footprint" "sa800u-baseboard-hw-footprints:R_0402_1005Metric" (id 2) (at 359.41 231.14 0)
      (effects (font (size 1.524 1.524)) (justify left) hide)
    )
    (property "Datasheet" "https://industrial.panasonic.com/cdbs/www-data/pdf/RDA0000/AOA0000C301.pdf" (id 3) (at 354.33 236.22 0)
      (effects (font (size 1.27 1.27)) hide)
    )
    (property "Manufacturer" "Panasonic" (id 4) (at 359.41 226.06 0)
      (effects (font (size 1.524 1.524)) (justify left) hide)
    )
    (property "MPN" "ERJ2GE0R00X" (id 5) (at 359.41 228.6 0)
      (effects (font (size 1.524 1.524)) (justify left) hide)
    )
    (property "Val" "0R" (id 6) (at 360.172 235.204 0))
    (property "DNP" "DNP" (id 7) (at 356.87 236.347 0))
    (property "License" "Apache-2.0" (id 8) (at 374.65 261.62 0)
      (effects (font (size 1.27 1.27) (thickness 0.15)) (justify left bottom) hide)
    )
    (property "Author" "Antmicro" (id 9) (at 374.65 264.16 0)
      (effects (font (size 1.27 1.27) (thickness 0.15)) (justify left bottom) hide)
    )
    (property "Tolerance" "~" (id 10) (at 374.65 246.38 0)
      (effects (font (size 1.27 1.27)) (justify left bottom) hide)
    )
    (property "Current" "1A" (id 11) (at 374.65 266.7 0)
      (effects (font (size 1.27 1.27) (thickness 0.15)) (justify left bottom) hide)
    )
    (pin "1")
    (pin "2")
  )

  (symbol (lib_id "sa800u-baseboard-hw:R_0R_0402") (at 354.33 213.868 0) (unit 1)
    (in_bom yes) (on_board yes)
    (property "Reference" "R2" (id 0) (at 353.314 212.725 0)
      (effects (font (size 1.524 1.524)))
    )
    (property "Value" "R_0R_0402" (id 1) (at 354.33 217.678 0)
      (effects (font (size 1.524 1.524)) hide)
    )
    (property "Footprint" "sa800u-baseboard-hw-footprints:R_0402_1005Metric" (id 2) (at 359.41 208.788 0)
      (effects (font (size 1.524 1.524)) (justify left) hide)
    )
    (property "Datasheet" "https://industrial.panasonic.com/cdbs/www-data/pdf/RDA0000/AOA0000C301.pdf" (id 3) (at 354.33 213.868 0)
      (effects (font (size 1.27 1.27)) hide)
    )
    (property "Manufacturer" "Panasonic" (id 4) (at 359.41 203.708 0)
      (effects (font (size 1.524 1.524)) (justify left) hide)
    )
    (property "MPN" "ERJ2GE0R00X" (id 5) (at 359.41 206.248 0)
      (effects (font (size 1.524 1.524)) (justify left) hide)
    )
    (property "Val" "0R" (id 6) (at 360.172 212.852 0))
    (property "DNP" "DNP" (id 7) (at 356.87 213.995 0))
    (property "License" "Apache-2.0" (id 8) (at 374.65 239.268 0)
      (effects (font (size 1.27 1.27) (thickness 0.15)) (justify left bottom) hide)
    )
    (property "Author" "Antmicro" (id 9) (at 374.65 241.808 0)
      (effects (font (size 1.27 1.27) (thickness 0.15)) (justify left bottom) hide)
    )
    (property "Tolerance" "~" (id 10) (at 374.65 224.028 0)
      (effects (font (size 1.27 1.27)) (justify left bottom) hide)
    )
    (property "Current" "1A" (id 11) (at 374.65 244.348 0)
      (effects (font (size 1.27 1.27) (thickness 0.15)) (justify left bottom) hide)
    )
    (pin "1")
    (pin "2")
  )

  (symbol (lib_id "sa800u-baseboard-hw:R_0R_0402") (at 354.33 204.978 0) (unit 1)
    (in_bom yes) (on_board yes)
    (property "Reference" "R1" (id 0) (at 353.314 203.835 0)
      (effects (font (size 1.524 1.524)))
    )
    (property "Value" "R_0R_0402" (id 1) (at 354.33 208.788 0)
      (effects (font (size 1.524 1.524)) hide)
    )
    (property "Footprint" "sa800u-baseboard-hw-footprints:R_0402_1005Metric" (id 2) (at 359.41 199.898 0)
      (effects (font (size 1.524 1.524)) (justify left) hide)
    )
    (property "Datasheet" "https://industrial.panasonic.com/cdbs/www-data/pdf/RDA0000/AOA0000C301.pdf" (id 3) (at 354.33 204.978 0)
      (effects (font (size 1.27 1.27)) hide)
    )
    (property "Manufacturer" "Panasonic" (id 4) (at 359.41 194.818 0)
      (effects (font (size 1.524 1.524)) (justify left) hide)
    )
    (property "MPN" "ERJ2GE0R00X" (id 5) (at 359.41 197.358 0)
      (effects (font (size 1.524 1.524)) (justify left) hide)
    )
    (property "Val" "0R" (id 6) (at 360.172 203.962 0))
    (property "DNP" "DNP" (id 7) (at 356.87 205.105 0))
    (property "License" "Apache-2.0" (id 8) (at 374.65 230.378 0)
      (effects (font (size 1.27 1.27) (thickness 0.15)) (justify left bottom) hide)
    )
    (property "Author" "Antmicro" (id 9) (at 374.65 232.918 0)
      (effects (font (size 1.27 1.27) (thickness 0.15)) (justify left bottom) hide)
    )
    (property "Tolerance" "~" (id 10) (at 374.65 215.138 0)
      (effects (font (size 1.27 1.27)) (justify left bottom) hide)
    )
    (property "Current" "1A" (id 11) (at 374.65 235.458 0)
      (effects (font (size 1.27 1.27) (thickness 0.15)) (justify left bottom) hide)
    )
    (pin "1")
    (pin "2")
  )

  (symbol (lib_id "sa800u-baseboard-hw:Earth") (at 349.25 237.49 0) (unit 1)
    (in_bom yes) (on_board yes)
    (property "Reference" "#PWR02" (id 0) (at 349.25 243.84 0)
      (effects (font (size 1.27 1.27)) hide)
    )
    (property "Value" "Earth" (id 1) (at 349.25 241.3 0)
      (effects (font (size 1.27 1.27)) hide)
    )
    (property "Footprint" "" (id 2) (at 349.25 237.49 0)
      (effects (font (size 1.27 1.27)) hide)
    )
    (property "Datasheet" "~" (id 3) (at 349.25 237.49 0)
      (effects (font (size 1.27 1.27)) hide)
    )
    (pin "1")
  )

  (sheet (at 139.7 123.19) (size 39.37 17.78) (fields_autoplaced)
    (stroke (width 0) (type solid) (color 0 0 0 0))
    (fill (color 0 0 0 0.0000))
    (property "Sheet name" "Ethernet Controller" (id 0) (at 139.7 122.4784 0)
      (effects (font (size 1.27 1.27)) (justify left bottom))
    )
    (property "Sheet file" "ethernet-controller.kicad_sch" (id 1) (at 139.7 141.5546 0)
      (effects (font (size 1.27 1.27)) (justify left top))
    )
  )

  (sheet (at 181.61 123.19) (size 39.37 17.78) (fields_autoplaced)
    (stroke (width 0) (type solid) (color 0 0 0 0))
    (fill (color 0 0 0 0.0000))
    (property "Sheet name" "HDMI converter" (id 0) (at 181.61 122.4784 0)
      (effects (font (size 1.27 1.27)) (justify left bottom))
    )
    (property "Sheet file" "hdmi-converter.kicad_sch" (id 1) (at 181.61 141.5546 0)
      (effects (font (size 1.27 1.27)) (justify left top))
    )
  )

  (sheet (at 97.79 123.19) (size 39.37 17.78) (fields_autoplaced)
    (stroke (width 0) (type solid) (color 0 0 0 0))
    (fill (color 0 0 0 0.0000))
    (property "Sheet name" "PoE" (id 0) (at 97.79 122.4784 0)
      (effects (font (size 1.27 1.27)) (justify left bottom))
    )
    (property "Sheet file" "poe.kicad_sch" (id 1) (at 97.79 141.5546 0)
      (effects (font (size 1.27 1.27)) (justify left top))
    )
  )

  (sheet (at 223.52 123.19) (size 39.37 17.78) (fields_autoplaced)
    (stroke (width 0) (type solid) (color 0 0 0 0))
    (fill (color 0 0 0 0.0000))
    (property "Sheet name" "USB-C Interface " (id 0) (at 223.52 122.4784 0)
      (effects (font (size 1.27 1.27)) (justify left bottom))
    )
    (property "Sheet file" "usb-c-interface.kicad_sch" (id 1) (at 223.52 141.5546 0)
      (effects (font (size 1.27 1.27)) (justify left top))
    )
  )

  (sheet (at 265.43 149.86) (size 39.37 17.78) (fields_autoplaced)
    (stroke (width 0) (type solid) (color 0 0 0 0))
    (fill (color 0 0 0 0.0000))
    (property "Sheet name" "SoM" (id 0) (at 265.43 149.1484 0)
      (effects (font (size 1.27 1.27)) (justify left bottom))
    )
    (property "Sheet file" "som.kicad_sch" (id 1) (at 265.43 168.2246 0)
      (effects (font (size 1.27 1.27)) (justify left top))
    )
  )

  (sheet (at 97.79 149.86) (size 39.37 17.78) (fields_autoplaced)
    (stroke (width 0) (type solid) (color 0 0 0 0))
    (fill (color 0 0 0 0.0000))
    (property "Sheet name" "Camera Interface" (id 0) (at 97.79 149.1484 0)
      (effects (font (size 1.27 1.27)) (justify left bottom))
    )
    (property "Sheet file" "camera-interface.kicad_sch" (id 1) (at 97.79 168.2246 0)
      (effects (font (size 1.27 1.27)) (justify left top))
    )
  )

  (sheet (at 223.52 149.86) (size 39.37 17.78) (fields_autoplaced)
    (stroke (width 0) (type solid) (color 0 0 0 0))
    (fill (color 0 0 0 0.0000))
    (property "Sheet name" "PSU" (id 0) (at 223.52 149.1484 0)
      (effects (font (size 1.27 1.27)) (justify left bottom))
    )
    (property "Sheet file" "psu.kicad_sch" (id 1) (at 223.52 168.2246 0)
      (effects (font (size 1.27 1.27)) (justify left top))
    )
  )

  (sheet (at 139.7 149.86) (size 39.37 17.78) (fields_autoplaced)
    (stroke (width 0) (type solid) (color 0 0 0 0))
    (fill (color 0 0 0 0.0000))
    (property "Sheet name" "M2" (id 0) (at 139.7 149.1484 0)
      (effects (font (size 1.27 1.27)) (justify left bottom))
    )
    (property "Sheet file" "m2.kicad_sch" (id 1) (at 139.7 168.2246 0)
      (effects (font (size 1.27 1.27)) (justify left top))
    )
  )

  (sheet (at 265.43 123.19) (size 39.37 17.78) (fields_autoplaced)
    (stroke (width 0) (type solid) (color 0 0 0 0))
    (fill (color 0 0 0 0.0000))
    (property "Sheet name" "LCM" (id 0) (at 265.43 122.4784 0)
      (effects (font (size 1.27 1.27)) (justify left bottom))
    )
    (property "Sheet file" "lcm.kicad_sch" (id 1) (at 265.43 141.5546 0)
      (effects (font (size 1.27 1.27)) (justify left top))
    )
  )

  (sheet (at 181.61 149.86) (size 39.37 17.78) (fields_autoplaced)
    (stroke (width 0) (type solid) (color 0 0 0 0))
    (fill (color 0 0 0 0.0000))
    (property "Sheet name" "Other Interfaces" (id 0) (at 181.61 149.1484 0)
      (effects (font (size 1.27 1.27)) (justify left bottom))
    )
    (property "Sheet file" "other-interfaces.kicad_sch" (id 1) (at 181.61 168.2246 0)
      (effects (font (size 1.27 1.27)) (justify left top))
    )
  )

  (sheet (at 223.52 176.53) (size 39.37 17.78) (fields_autoplaced)
    (stroke (width 0) (type solid) (color 0 0 0 0))
    (fill (color 0 0 0 0.0000))
    (property "Sheet name" "USB-PD" (id 0) (at 223.52 175.8184 0)
      (effects (font (size 1.27 1.27)) (justify left bottom))
    )
    (property "Sheet file" "usb-pd.kicad_sch" (id 1) (at 223.52 194.8946 0)
      (effects (font (size 1.27 1.27)) (justify left top))
    )
  )

  (sheet_instances
    (path "/" (page "1"))
    (path "" (page "2"))
    (path "" (page "3"))
    (path "" (page "4"))
    (path "" (page "5"))
    (path "" (page "6"))
    (path "" (page "7"))
    (path "" (page "8"))
    (path "" (page "9"))
    (path "" (page "10"))
    (path "" (page "11"))
    (path "" (page "12"))
  )

  (symbol_instances
    (path ""
      (reference "#FLG01") (unit 1) (value "PWR_FLAG") (footprint "")
    )
    (path ""
      (reference "#FLG02") (unit 1) (value "PWR_FLAG") (footprint "")
    )
    (path ""
      (reference "#FLG03") (unit 1) (value "PWR_FLAG") (footprint "")
    )
    (path ""
      (reference "#FLG04") (unit 1) (value "PWR_FLAG") (footprint "")
    )
    (path ""
      (reference "#FLG05") (unit 1) (value "PWR_FLAG") (footprint "")
    )
    (path ""
      (reference "#FLG06") (unit 1) (value "PWR_FLAG") (footprint "")
    )
    (path ""
      (reference "#FLG07") (unit 1) (value "PWR_FLAG") (footprint "")
    )
    (path ""
      (reference "#FLG08") (unit 1) (value "PWR_FLAG") (footprint "")
    )
    (path ""
      (reference "#FLG09") (unit 1) (value "PWR_FLAG") (footprint "")
    )
    (path ""
      (reference "#FLG010") (unit 1) (value "PWR_FLAG") (footprint "")
    )
    (path ""
      (reference "#FLG011") (unit 1) (value "PWR_FLAG") (footprint "")
    )
    (path ""
      (reference "#FLG012") (unit 1) (value "PWR_FLAG") (footprint "")
    )
    (path ""
      (reference "#FLG013") (unit 1) (value "PWR_FLAG") (footprint "")
    )
    (path ""
      (reference "#FLG014") (unit 1) (value "PWR_FLAG") (footprint "")
    )
    (path ""
      (reference "#FLG015") (unit 1) (value "PWR_FLAG") (footprint "")
    )
    (path ""
      (reference "#FLG016") (unit 1) (value "PWR_FLAG") (footprint "")
    )
    (path ""
      (reference "#FLG017") (unit 1) (value "PWR_FLAG") (footprint "")
    )
    (path ""
      (reference "#FLG018") (unit 1) (value "PWR_FLAG") (footprint "")
    )
    (path ""
      (reference "#FLG019") (unit 1) (value "PWR_FLAG") (footprint "")
    )
    (path ""
      (reference "#FLG020") (unit 1) (value "PWR_FLAG") (footprint "")
    )
    (path ""
      (reference "#FLG021") (unit 1) (value "PWR_FLAG") (footprint "")
    )
    (path ""
      (reference "#FLG022") (unit 1) (value "PWR_FLAG") (footprint "")
    )
    (path ""
      (reference "#FLG023") (unit 1) (value "PWR_FLAG") (footprint "")
    )
    (path ""
      (reference "#FLG024") (unit 1) (value "PWR_FLAG") (footprint "")
    )
    (path ""
      (reference "#FLG025") (unit 1) (value "PWR_FLAG") (footprint "")
    )
    (path ""
      (reference "#FLG026") (unit 1) (value "PWR_FLAG") (footprint "")
    )
    (path ""
      (reference "#FLG027") (unit 1) (value "PWR_FLAG") (footprint "")
    )
    (path ""
      (reference "#FLG028") (unit 1) (value "PWR_FLAG") (footprint "")
    )
    (path ""
      (reference "#FLG0101") (unit 1) (value "PWR_FLAG") (footprint "")
    )
    (path ""
      (reference "#FLG0102") (unit 1) (value "PWR_FLAG") (footprint "")
    )
    (path ""
      (reference "#FLG0103") (unit 1) (value "PWR_FLAG") (footprint "")
    )
    (path ""
      (reference "#FLG0104") (unit 1) (value "PWR_FLAG") (footprint "")
    )
    (path ""
      (reference "#FLG0105") (unit 1) (value "PWR_FLAG") (footprint "")
    )
    (path ""
      (reference "#FLG0106") (unit 1) (value "PWR_FLAG") (footprint "")
    )
    (path ""
      (reference "#FLG0107") (unit 1) (value "PWR_FLAG") (footprint "")
    )
    (path ""
      (reference "#FLG0108") (unit 1) (value "PWR_FLAG") (footprint "")
    )
    (path ""
      (reference "#FLG0109") (unit 1) (value "PWR_FLAG") (footprint "")
    )
    (path ""
      (reference "#PWR01") (unit 1) (value "GND") (footprint "")
    )
    (path ""
      (reference "#PWR02") (unit 1) (value "Earth") (footprint "")
    )
    (path ""
      (reference "#PWR04") (unit 1) (value "GND") (footprint "")
    )
    (path ""
      (reference "#PWR05") (unit 1) (value "GND") (footprint "")
    )
    (path ""
      (reference "#PWR06") (unit 1) (value "GND") (footprint "")
    )
    (path ""
      (reference "#PWR07") (unit 1) (value "GND") (footprint "")
    )
    (path ""
      (reference "#PWR09") (unit 1) (value "GND") (footprint "")
    )
    (path ""
      (reference "#PWR010") (unit 1) (value "Earth") (footprint "")
    )
    (path ""
      (reference "#PWR011") (unit 1) (value "Earth") (footprint "")
    )
    (path ""
      (reference "#PWR012") (unit 1) (value "GND") (footprint "")
    )
    (path ""
      (reference "#PWR013") (unit 1) (value "GND") (footprint "")
    )
    (path ""
      (reference "#PWR014") (unit 1) (value "GND") (footprint "")
    )
    (path ""
      (reference "#PWR015") (unit 1) (value "GND") (footprint "")
    )
    (path ""
      (reference "#PWR016") (unit 1) (value "GND") (footprint "")
    )
    (path ""
      (reference "#PWR017") (unit 1) (value "GND") (footprint "")
    )
    (path ""
      (reference "#PWR018") (unit 1) (value "GND") (footprint "")
    )
    (path ""
      (reference "#PWR019") (unit 1) (value "GND") (footprint "")
    )
    (path ""
      (reference "#PWR021") (unit 1) (value "GND") (footprint "")
    )
    (path ""
      (reference "#PWR022") (unit 1) (value "GND") (footprint "")
    )
    (path ""
      (reference "#PWR023") (unit 1) (value "GND") (footprint "")
    )
    (path ""
      (reference "#PWR024") (unit 1) (value "GND") (footprint "")
    )
    (path ""
      (reference "#PWR025") (unit 1) (value "GND") (footprint "")
    )
    (path ""
      (reference "#PWR026") (unit 1) (value "GND") (footprint "")
    )
    (path ""
      (reference "#PWR027") (unit 1) (value "GND") (footprint "")
    )
    (path ""
      (reference "#PWR028") (unit 1) (value "GND") (footprint "")
    )
    (path ""
      (reference "#PWR029") (unit 1) (value "GND") (footprint "")
    )
    (path ""
      (reference "#PWR030") (unit 1) (value "GND") (footprint "")
    )
    (path ""
      (reference "#PWR031") (unit 1) (value "GND") (footprint "")
    )
    (path ""
      (reference "#PWR032") (unit 1) (value "GND") (footprint "")
    )
    (path ""
      (reference "#PWR033") (unit 1) (value "GND") (footprint "")
    )
    (path ""
      (reference "#PWR034") (unit 1) (value "GND") (footprint "")
    )
    (path ""
      (reference "#PWR035") (unit 1) (value "GND") (footprint "")
    )
    (path ""
      (reference "#PWR036") (unit 1) (value "GND") (footprint "")
    )
    (path ""
      (reference "#PWR038") (unit 1) (value "GND") (footprint "")
    )
    (path ""
      (reference "#PWR039") (unit 1) (value "GND") (footprint "")
    )
    (path ""
      (reference "#PWR040") (unit 1) (value "GND") (footprint "")
    )
    (path ""
      (reference "#PWR041") (unit 1) (value "GND") (footprint "")
    )
    (path ""
      (reference "#PWR042") (unit 1) (value "GND") (footprint "")
    )
    (path ""
      (reference "#PWR043") (unit 1) (value "GND") (footprint "")
    )
    (path ""
      (reference "#PWR044") (unit 1) (value "GND") (footprint "")
    )
    (path ""
      (reference "#PWR045") (unit 1) (value "GND") (footprint "")
    )
    (path ""
      (reference "#PWR046") (unit 1) (value "GND") (footprint "")
    )
    (path ""
      (reference "#PWR047") (unit 1) (value "GND") (footprint "")
    )
    (path ""
      (reference "#PWR049") (unit 1) (value "GND") (footprint "")
    )
    (path ""
      (reference "#PWR050") (unit 1) (value "GND") (footprint "")
    )
    (path ""
      (reference "#PWR051") (unit 1) (value "GND") (footprint "")
    )
    (path ""
      (reference "#PWR052") (unit 1) (value "GND") (footprint "")
    )
    (path ""
      (reference "#PWR053") (unit 1) (value "GND") (footprint "")
    )
    (path ""
      (reference "#PWR054") (unit 1) (value "GND") (footprint "")
    )
    (path ""
      (reference "#PWR055") (unit 1) (value "GND") (footprint "")
    )
    (path ""
      (reference "#PWR056") (unit 1) (value "GND") (footprint "")
    )
    (path ""
      (reference "#PWR057") (unit 1) (value "GND") (footprint "")
    )
    (path ""
      (reference "#PWR058") (unit 1) (value "GND") (footprint "")
    )
    (path ""
      (reference "#PWR059") (unit 1) (value "GND") (footprint "")
    )
    (path ""
      (reference "#PWR060") (unit 1) (value "GND") (footprint "")
    )
    (path ""
      (reference "#PWR061") (unit 1) (value "GND") (footprint "")
    )
    (path ""
      (reference "#PWR062") (unit 1) (value "GND") (footprint "")
    )
    (path ""
      (reference "#PWR063") (unit 1) (value "GND") (footprint "")
    )
    (path ""
      (reference "#PWR064") (unit 1) (value "GND") (footprint "")
    )
    (path ""
      (reference "#PWR065") (unit 1) (value "GND") (footprint "")
    )
    (path ""
      (reference "#PWR066") (unit 1) (value "GND") (footprint "")
    )
    (path ""
      (reference "#PWR067") (unit 1) (value "GND") (footprint "")
    )
    (path ""
      (reference "#PWR068") (unit 1) (value "GND") (footprint "")
    )
    (path ""
      (reference "#PWR069") (unit 1) (value "GND") (footprint "")
    )
    (path ""
      (reference "#PWR070") (unit 1) (value "GND") (footprint "")
    )
    (path ""
      (reference "#PWR071") (unit 1) (value "GND") (footprint "")
    )
    (path ""
      (reference "#PWR072") (unit 1) (value "GND") (footprint "")
    )
    (path ""
      (reference "#PWR073") (unit 1) (value "GND") (footprint "")
    )
    (path ""
      (reference "#PWR074") (unit 1) (value "GND") (footprint "")
    )
    (path ""
      (reference "#PWR075") (unit 1) (value "GND") (footprint "")
    )
    (path ""
      (reference "#PWR076") (unit 1) (value "GND") (footprint "")
    )
    (path ""
      (reference "#PWR077") (unit 1) (value "GND") (footprint "")
    )
    (path ""
      (reference "#PWR078") (unit 1) (value "GND") (footprint "")
    )
    (path ""
      (reference "#PWR079") (unit 1) (value "GND") (footprint "")
    )
    (path ""
      (reference "#PWR080") (unit 1) (value "GND") (footprint "")
    )
    (path ""
      (reference "#PWR081") (unit 1) (value "GND") (footprint "")
    )
    (path ""
      (reference "#PWR082") (unit 1) (value "GND") (footprint "")
    )
    (path ""
      (reference "#PWR083") (unit 1) (value "GND") (footprint "")
    )
    (path ""
      (reference "#PWR084") (unit 1) (value "GND") (footprint "")
    )
    (path ""
      (reference "#PWR085") (unit 1) (value "GND") (footprint "")
    )
    (path ""
      (reference "#PWR086") (unit 1) (value "GND") (footprint "")
    )
    (path ""
      (reference "#PWR0101") (unit 1) (value "GND") (footprint "")
    )
    (path ""
      (reference "#PWR0102") (unit 1) (value "GND") (footprint "")
    )
    (path ""
      (reference "#PWR0103") (unit 1) (value "GND") (footprint "")
    )
    (path ""
      (reference "#PWR0104") (unit 1) (value "GND") (footprint "")
    )
    (path ""
      (reference "#PWR0105") (unit 1) (value "GND") (footprint "")
    )
    (path ""
      (reference "#PWR0106") (unit 1) (value "GNDD") (footprint "")
    )
    (path ""
      (reference "#PWR0141") (unit 1) (value "GND") (footprint "")
    )
    (path ""
      (reference "#PWR0159") (unit 1) (value "GND") (footprint "")
    )
    (path ""
      (reference "#PWR0160") (unit 1) (value "GND") (footprint "")
    )
    (path ""
      (reference "#PWR0161") (unit 1) (value "GND") (footprint "")
    )
    (path ""
      (reference "#PWR0162") (unit 1) (value "GND") (footprint "")
    )
    (path ""
      (reference "#PWR0163") (unit 1) (value "GND") (footprint "")
    )
    (path ""
      (reference "#PWR0164") (unit 1) (value "GND") (footprint "")
    )
    (path ""
      (reference "#PWR0165") (unit 1) (value "GND") (footprint "")
    )
    (path ""
      (reference "#PWR0166") (unit 1) (value "GND") (footprint "")
    )
    (path ""
      (reference "#PWR0167") (unit 1) (value "GND") (footprint "")
    )
    (path ""
      (reference "#PWR0168") (unit 1) (value "GND") (footprint "")
    )
    (path ""
      (reference "#PWR0169") (unit 1) (value "GND") (footprint "")
    )
    (path ""
      (reference "#PWR0170") (unit 1) (value "GND") (footprint "")
    )
    (path ""
      (reference "#PWR0171") (unit 1) (value "GND") (footprint "")
    )
    (path ""
      (reference "#PWR0172") (unit 1) (value "GND") (footprint "")
    )
    (path ""
      (reference "#PWR0173") (unit 1) (value "GND") (footprint "")
    )
    (path ""
      (reference "#PWR0174") (unit 1) (value "GND") (footprint "")
    )
    (path ""
      (reference "#PWR0175") (unit 1) (value "GND") (footprint "")
    )
    (path ""
      (reference "#PWR0176") (unit 1) (value "GND") (footprint "")
    )
    (path ""
      (reference "#PWR0177") (unit 1) (value "GND") (footprint "")
    )
    (path ""
      (reference "#PWR0178") (unit 1) (value "GND") (footprint "")
    )
    (path ""
      (reference "#PWR0179") (unit 1) (value "GND") (footprint "")
    )
    (path ""
      (reference "#PWR0180") (unit 1) (value "GND") (footprint "")
    )
    (path ""
      (reference "#PWR0181") (unit 1) (value "GND") (footprint "")
    )
    (path ""
      (reference "#PWR0182") (unit 1) (value "GND") (footprint "")
    )
    (path ""
      (reference "#PWR0183") (unit 1) (value "GND") (footprint "")
    )
    (path ""
      (reference "#PWR0184") (unit 1) (value "GND") (footprint "")
    )
    (path ""
      (reference "#PWR0185") (unit 1) (value "GND") (footprint "")
    )
    (path ""
      (reference "#PWR0186") (unit 1) (value "GND") (footprint "")
    )
    (path ""
      (reference "#PWR0187") (unit 1) (value "GND") (footprint "")
    )
    (path ""
      (reference "#PWR0189") (unit 1) (value "GND") (footprint "")
    )
    (path ""
      (reference "#PWR0190") (unit 1) (value "GND") (footprint "")
    )
    (path ""
      (reference "#PWR0191") (unit 1) (value "GND") (footprint "")
    )
    (path ""
      (reference "#PWR0192") (unit 1) (value "GND") (footprint "")
    )
    (path ""
      (reference "#PWR0193") (unit 1) (value "GND") (footprint "")
    )
    (path ""
      (reference "#PWR0194") (unit 1) (value "GND") (footprint "")
    )
    (path ""
      (reference "#PWR0195") (unit 1) (value "GND") (footprint "")
    )
    (path ""
      (reference "#PWR0196") (unit 1) (value "GND") (footprint "")
    )
    (path ""
      (reference "#PWR0197") (unit 1) (value "GND") (footprint "")
    )
    (path ""
      (reference "#PWR0198") (unit 1) (value "GND") (footprint "")
    )
    (path ""
      (reference "#PWR0199") (unit 1) (value "GND") (footprint "")
    )
    (path ""
      (reference "#PWR0200") (unit 1) (value "GND") (footprint "")
    )
    (path ""
      (reference "#PWR0201") (unit 1) (value "GND") (footprint "")
    )
    (path ""
      (reference "#PWR0202") (unit 1) (value "GND") (footprint "")
    )
    (path ""
      (reference "#PWR0203") (unit 1) (value "GND") (footprint "")
    )
    (path ""
      (reference "#PWR0204") (unit 1) (value "GND") (footprint "")
    )
    (path ""
      (reference "#PWR0205") (unit 1) (value "GND") (footprint "")
    )
    (path ""
      (reference "#PWR0206") (unit 1) (value "GND") (footprint "")
    )
    (path ""
      (reference "#PWR0207") (unit 1) (value "GND") (footprint "")
    )
    (path ""
      (reference "#PWR0208") (unit 1) (value "GND") (footprint "")
    )
    (path ""
      (reference "#PWR0209") (unit 1) (value "GND") (footprint "")
    )
    (path ""
      (reference "#PWR0210") (unit 1) (value "GND") (footprint "")
    )
    (path ""
      (reference "#PWR0211") (unit 1) (value "GND") (footprint "")
    )
    (path ""
      (reference "#PWR0212") (unit 1) (value "GND") (footprint "")
    )
    (path ""
      (reference "#PWR0213") (unit 1) (value "GND") (footprint "")
    )
    (path ""
      (reference "#PWR0214") (unit 1) (value "GND") (footprint "")
    )
    (path ""
      (reference "#PWR0215") (unit 1) (value "GND") (footprint "")
    )
    (path ""
      (reference "#PWR0216") (unit 1) (value "GND") (footprint "")
    )
    (path ""
      (reference "#PWR0217") (unit 1) (value "GND") (footprint "")
    )
    (path ""
      (reference "#PWR0218") (unit 1) (value "GND") (footprint "")
    )
    (path ""
      (reference "#PWR0219") (unit 1) (value "GND") (footprint "")
    )
    (path ""
      (reference "#PWR0220") (unit 1) (value "GND") (footprint "")
    )
    (path ""
      (reference "#PWR0221") (unit 1) (value "GND") (footprint "")
    )
    (path ""
      (reference "#PWR0222") (unit 1) (value "GND") (footprint "")
    )
    (path ""
      (reference "#PWR0223") (unit 1) (value "GND") (footprint "")
    )
    (path ""
      (reference "#PWR0224") (unit 1) (value "GND") (footprint "")
    )
    (path ""
      (reference "#PWR0225") (unit 1) (value "GND") (footprint "")
    )
    (path ""
      (reference "#PWR0226") (unit 1) (value "GND") (footprint "")
    )
    (path ""
      (reference "#PWR0227") (unit 1) (value "GND") (footprint "")
    )
    (path ""
      (reference "#PWR0228") (unit 1) (value "GND") (footprint "")
    )
    (path ""
      (reference "#PWR0229") (unit 1) (value "GND") (footprint "")
    )
    (path ""
      (reference "#PWR0230") (unit 1) (value "GND") (footprint "")
    )
    (path ""
      (reference "#PWR0231") (unit 1) (value "GND") (footprint "")
    )
    (path ""
      (reference "#PWR0232") (unit 1) (value "GND") (footprint "")
    )
    (path ""
      (reference "#PWR0233") (unit 1) (value "GND") (footprint "")
    )
    (path ""
      (reference "#PWR0234") (unit 1) (value "GND") (footprint "")
    )
    (path ""
      (reference "#PWR0235") (unit 1) (value "GND") (footprint "")
    )
    (path ""
      (reference "#PWR0236") (unit 1) (value "GND") (footprint "")
    )
    (path ""
      (reference "#PWR0237") (unit 1) (value "GND") (footprint "")
    )
    (path ""
      (reference "#PWR0238") (unit 1) (value "GND") (footprint "")
    )
    (path ""
      (reference "#PWR0239") (unit 1) (value "GND") (footprint "")
    )
    (path ""
      (reference "#PWR0240") (unit 1) (value "GND") (footprint "")
    )
    (path ""
      (reference "#PWR0241") (unit 1) (value "GND") (footprint "")
    )
    (path ""
      (reference "#PWR0242") (unit 1) (value "GND") (footprint "")
    )
    (path ""
      (reference "#PWR0243") (unit 1) (value "GNDD") (footprint "")
    )
    (path ""
      (reference "#PWR0244") (unit 1) (value "GNDD") (footprint "")
    )
    (path ""
      (reference "#PWR0245") (unit 1) (value "GNDD") (footprint "")
    )
    (path ""
      (reference "#PWR0246") (unit 1) (value "GNDD") (footprint "")
    )
    (path ""
      (reference "#PWR0247") (unit 1) (value "GNDD") (footprint "")
    )
    (path ""
      (reference "#PWR0248") (unit 1) (value "GNDD") (footprint "")
    )
    (path ""
      (reference "#PWR0249") (unit 1) (value "GNDD") (footprint "")
    )
    (path ""
      (reference "#PWR0250") (unit 1) (value "GND") (footprint "")
    )
    (path ""
      (reference "#PWR0251") (unit 1) (value "GND") (footprint "")
    )
    (path ""
      (reference "#PWR0252") (unit 1) (value "GND") (footprint "")
    )
    (path ""
      (reference "#PWR0253") (unit 1) (value "GND") (footprint "")
    )
    (path ""
      (reference "#PWR0254") (unit 1) (value "GND") (footprint "")
    )
    (path ""
      (reference "#PWR0255") (unit 1) (value "GND") (footprint "")
    )
    (path ""
      (reference "#PWR0256") (unit 1) (value "GND") (footprint "")
    )
    (path ""
      (reference "#PWR0257") (unit 1) (value "GND") (footprint "")
    )
    (path ""
      (reference "#PWR0258") (unit 1) (value "GND") (footprint "")
    )
    (path ""
      (reference "#PWR0259") (unit 1) (value "GND") (footprint "")
    )
    (path ""
      (reference "#PWR0260") (unit 1) (value "GND") (footprint "")
    )
    (path ""
      (reference "#PWR0261") (unit 1) (value "GND") (footprint "")
    )
    (path ""
      (reference "#PWR0262") (unit 1) (value "GND") (footprint "")
    )
    (path ""
      (reference "#PWR0264") (unit 1) (value "GND") (footprint "")
    )
    (path ""
      (reference "#PWR0265") (unit 1) (value "GND") (footprint "")
    )
    (path ""
      (reference "#PWR0266") (unit 1) (value "GND") (footprint "")
    )
    (path ""
      (reference "#PWR0267") (unit 1) (value "GND") (footprint "")
    )
    (path ""
      (reference "#PWR0268") (unit 1) (value "GND") (footprint "")
    )
    (path ""
      (reference "#PWR0269") (unit 1) (value "GND") (footprint "")
    )
    (path ""
      (reference "#PWR0270") (unit 1) (value "GND") (footprint "")
    )
    (path ""
      (reference "#PWR0271") (unit 1) (value "GND") (footprint "")
    )
    (path ""
      (reference "A1") (unit 1) (value "SA800U-WF") (footprint "sa800u-baseboard-hw-footprints:SA800U-WF")
    )
    (path ""
      (reference "BAT1") (unit 1) (value "Battery_Holder_MS621FE-FL11E") (footprint "sa800u-baseboard-hw-footprints:MS621FE-FL11E")
    )
    (path ""
      (reference "C1") (unit 1) (value "C_10p_0402") (footprint "sa800u-baseboard-hw-footprints:C_0402_1005Metric")
    )
    (path ""
      (reference "C2") (unit 1) (value "C_10p_0402") (footprint "sa800u-baseboard-hw-footprints:C_0402_1005Metric")
    )
    (path ""
      (reference "C3") (unit 1) (value "C_100n_0402") (footprint "sa800u-baseboard-hw-footprints:C_0402_1005Metric")
    )
    (path ""
      (reference "C4") (unit 1) (value "C_100n_0402") (footprint "sa800u-baseboard-hw-footprints:C_0402_1005Metric")
    )
    (path ""
      (reference "C5") (unit 1) (value "C_100n_0402") (footprint "sa800u-baseboard-hw-footprints:C_0402_1005Metric")
    )
    (path ""
      (reference "C6") (unit 1) (value "C_100n_0402") (footprint "sa800u-baseboard-hw-footprints:C_0402_1005Metric")
    )
    (path ""
      (reference "C7") (unit 1) (value "C_100n_0402") (footprint "sa800u-baseboard-hw-footprints:C_0402_1005Metric")
    )
    (path ""
      (reference "C8") (unit 1) (value "C_4u7_0402") (footprint "sa800u-baseboard-hw-footprints:C_0402_1005Metric")
    )
    (path ""
      (reference "C9") (unit 1) (value "C_4u7_0402") (footprint "sa800u-baseboard-hw-footprints:C_0402_1005Metric")
    )
    (path ""
      (reference "C10") (unit 1) (value "C_4u7_0402") (footprint "sa800u-baseboard-hw-footprints:C_0402_1005Metric")
    )
    (path ""
      (reference "C11") (unit 1) (value "C_100n_0402") (footprint "sa800u-baseboard-hw-footprints:C_0402_1005Metric")
    )
    (path ""
      (reference "C12") (unit 1) (value "C_100n_0402") (footprint "sa800u-baseboard-hw-footprints:C_0402_1005Metric")
    )
    (path ""
      (reference "C13") (unit 1) (value "C_100n_0402") (footprint "sa800u-baseboard-hw-footprints:C_0402_1005Metric")
    )
    (path ""
      (reference "C14") (unit 1) (value "C_100n_0402") (footprint "sa800u-baseboard-hw-footprints:C_0402_1005Metric")
    )
    (path ""
      (reference "C15") (unit 1) (value "C_100n_0402") (footprint "sa800u-baseboard-hw-footprints:C_0402_1005Metric")
    )
    (path ""
      (reference "C16") (unit 1) (value "C_10n_0402") (footprint "sa800u-baseboard-hw-footprints:C_0402_1005Metric")
    )
    (path ""
      (reference "C17") (unit 1) (value "C_1u_0402") (footprint "sa800u-baseboard-hw-footprints:C_0402_1005Metric")
    )
    (path ""
      (reference "C18") (unit 1) (value "C_100n_0402") (footprint "sa800u-baseboard-hw-footprints:C_0402_1005Metric")
    )
    (path ""
      (reference "C19") (unit 1) (value "C_15p_0402") (footprint "sa800u-baseboard-hw-footprints:C_0402_1005Metric")
    )
    (path ""
      (reference "C20") (unit 1) (value "C_100n_0402") (footprint "sa800u-baseboard-hw-footprints:C_0402_1005Metric")
    )
    (path ""
      (reference "C21") (unit 1) (value "C_15p_0402") (footprint "sa800u-baseboard-hw-footprints:C_0402_1005Metric")
    )
    (path ""
      (reference "C22") (unit 1) (value "C_10u_0402") (footprint "sa800u-baseboard-hw-footprints:C_0402_1005Metric")
    )
    (path ""
      (reference "C23") (unit 1) (value "C_10u_0402") (footprint "sa800u-baseboard-hw-footprints:C_0402_1005Metric")
    )
    (path ""
      (reference "C24") (unit 1) (value "C_10u_0402") (footprint "sa800u-baseboard-hw-footprints:C_0402_1005Metric")
    )
    (path ""
      (reference "C25") (unit 1) (value "C_1u_0402") (footprint "sa800u-baseboard-hw-footprints:C_0402_1005Metric")
    )
    (path ""
      (reference "C26") (unit 1) (value "C_1u_0402") (footprint "sa800u-baseboard-hw-footprints:C_0402_1005Metric")
    )
    (path ""
      (reference "C27") (unit 1) (value "C_100n_0402") (footprint "sa800u-baseboard-hw-footprints:C_0402_1005Metric")
    )
    (path ""
      (reference "C28") (unit 1) (value "C_100n_0402") (footprint "sa800u-baseboard-hw-footprints:C_0402_1005Metric")
    )
    (path ""
      (reference "C29") (unit 1) (value "C_100n_0402") (footprint "sa800u-baseboard-hw-footprints:C_0402_1005Metric")
    )
    (path ""
      (reference "C30") (unit 1) (value "C_100n_0402") (footprint "sa800u-baseboard-hw-footprints:C_0402_1005Metric")
    )
    (path ""
      (reference "C31") (unit 1) (value "C_100n_0402") (footprint "sa800u-baseboard-hw-footprints:C_0402_1005Metric")
    )
    (path ""
      (reference "C32") (unit 1) (value "C_100n_0402") (footprint "sa800u-baseboard-hw-footprints:C_0402_1005Metric")
    )
    (path ""
      (reference "C33") (unit 1) (value "C_100n_0402") (footprint "sa800u-baseboard-hw-footprints:C_0402_1005Metric")
    )
    (path ""
      (reference "C34") (unit 1) (value "C_1u_0402") (footprint "sa800u-baseboard-hw-footprints:C_0402_1005Metric")
    )
    (path ""
      (reference "C35") (unit 1) (value "C_100n_0402") (footprint "sa800u-baseboard-hw-footprints:C_0402_1005Metric")
    )
    (path ""
      (reference "C36") (unit 1) (value "C_10u_0402") (footprint "sa800u-baseboard-hw-footprints:C_0402_1005Metric")
    )
    (path ""
      (reference "C37") (unit 1) (value "C_100n_0402") (footprint "sa800u-baseboard-hw-footprints:C_0402_1005Metric")
    )
    (path ""
      (reference "C38") (unit 1) (value "C_10u_0402") (footprint "sa800u-baseboard-hw-footprints:C_0402_1005Metric")
    )
    (path ""
      (reference "C39") (unit 1) (value "C_100n_0402") (footprint "sa800u-baseboard-hw-footprints:C_0402_1005Metric")
    )
    (path ""
      (reference "C40") (unit 1) (value "C_100n_0402") (footprint "sa800u-baseboard-hw-footprints:C_0402_1005Metric")
    )
    (path ""
      (reference "C41") (unit 1) (value "C_100n_0402") (footprint "sa800u-baseboard-hw-footprints:C_0402_1005Metric")
    )
    (path ""
      (reference "C42") (unit 1) (value "C_100n_0402") (footprint "sa800u-baseboard-hw-footprints:C_0402_1005Metric")
    )
    (path ""
      (reference "C43") (unit 1) (value "C_10u_0402") (footprint "sa800u-baseboard-hw-footprints:C_0402_1005Metric")
    )
    (path ""
      (reference "C44") (unit 1) (value "C_100n_0402") (footprint "sa800u-baseboard-hw-footprints:C_0402_1005Metric")
    )
    (path ""
      (reference "C45") (unit 1) (value "C_100n_0402") (footprint "sa800u-baseboard-hw-footprints:C_0402_1005Metric")
    )
    (path ""
      (reference "C46") (unit 1) (value "C_100n_0402") (footprint "sa800u-baseboard-hw-footprints:C_0402_1005Metric")
    )
    (path ""
      (reference "C47") (unit 1) (value "C_100n_0402") (footprint "sa800u-baseboard-hw-footprints:C_0402_1005Metric")
    )
    (path ""
      (reference "C48") (unit 1) (value "C_100n_0402") (footprint "sa800u-baseboard-hw-footprints:C_0402_1005Metric")
    )
    (path ""
      (reference "C49") (unit 1) (value "C_100n_0402") (footprint "sa800u-baseboard-hw-footprints:C_0402_1005Metric")
    )
    (path ""
      (reference "C50") (unit 1) (value "C_100n_0402") (footprint "sa800u-baseboard-hw-footprints:C_0402_1005Metric")
    )
    (path ""
      (reference "C51") (unit 1) (value "C_100n_0402") (footprint "sa800u-baseboard-hw-footprints:C_0402_1005Metric")
    )
    (path ""
      (reference "C52") (unit 1) (value "C_100n_0402") (footprint "sa800u-baseboard-hw-footprints:C_0402_1005Metric")
    )
    (path ""
      (reference "C53") (unit 1) (value "C_100n_0402") (footprint "sa800u-baseboard-hw-footprints:C_0402_1005Metric")
    )
    (path ""
      (reference "C54") (unit 1) (value "C_100n_0402") (footprint "sa800u-baseboard-hw-footprints:C_0402_1005Metric")
    )
    (path ""
      (reference "C55") (unit 1) (value "C_100n_0402") (footprint "sa800u-baseboard-hw-footprints:C_0402_1005Metric")
    )
    (path ""
      (reference "C56") (unit 1) (value "C_10p_0402") (footprint "sa800u-baseboard-hw-footprints:C_0402_1005Metric")
    )
    (path ""
      (reference "C57") (unit 1) (value "C_10p_0402") (footprint "sa800u-baseboard-hw-footprints:C_0402_1005Metric")
    )
    (path ""
      (reference "C58") (unit 1) (value "C_47u_0603") (footprint "sa800u-baseboard-hw-footprints:C_0603_1608Metric")
    )
    (path ""
      (reference "C59") (unit 1) (value "C_47u_0603") (footprint "sa800u-baseboard-hw-footprints:C_0603_1608Metric")
    )
    (path ""
      (reference "C60") (unit 1) (value "C_100n_0402") (footprint "sa800u-baseboard-hw-footprints:C_0402_1005Metric")
    )
    (path ""
      (reference "C61") (unit 1) (value "C_100n_0402") (footprint "sa800u-baseboard-hw-footprints:C_0402_1005Metric")
    )
    (path ""
      (reference "C62") (unit 1) (value "C_47u_0603") (footprint "sa800u-baseboard-hw-footprints:C_0603_1608Metric")
    )
    (path ""
      (reference "C63") (unit 1) (value "C_100n_0402") (footprint "sa800u-baseboard-hw-footprints:C_0402_1005Metric")
    )
    (path ""
      (reference "C64") (unit 1) (value "C_100n_0402") (footprint "sa800u-baseboard-hw-footprints:C_0402_1005Metric")
    )
    (path ""
      (reference "C65") (unit 1) (value "C_100n_0402") (footprint "sa800u-baseboard-hw-footprints:C_0402_1005Metric")
    )
    (path ""
      (reference "C66") (unit 1) (value "C_1u_0402") (footprint "sa800u-baseboard-hw-footprints:C_0402_1005Metric")
    )
    (path ""
      (reference "C67") (unit 1) (value "C_100n_0402") (footprint "sa800u-baseboard-hw-footprints:C_0402_1005Metric")
    )
    (path ""
      (reference "C68") (unit 1) (value "C_47p_0402") (footprint "sa800u-baseboard-hw-footprints:C_0402_1005Metric")
    )
    (path ""
      (reference "C69") (unit 1) (value "C_100n_0402") (footprint "sa800u-baseboard-hw-footprints:C_0402_1005Metric")
    )
    (path ""
      (reference "C70") (unit 1) (value "C_47p_0402") (footprint "sa800u-baseboard-hw-footprints:C_0402_1005Metric")
    )
    (path ""
      (reference "C71") (unit 1) (value "C_10u_0402") (footprint "sa800u-baseboard-hw-footprints:C_0402_1005Metric")
    )
    (path ""
      (reference "C72") (unit 1) (value "C_100n_0402") (footprint "sa800u-baseboard-hw-footprints:C_0402_1005Metric")
    )
    (path ""
      (reference "C73") (unit 1) (value "C_100n_0402") (footprint "sa800u-baseboard-hw-footprints:C_0402_1005Metric")
    )
    (path ""
      (reference "C74") (unit 1) (value "C_100n_0402") (footprint "sa800u-baseboard-hw-footprints:C_0402_1005Metric")
    )
    (path ""
      (reference "C75") (unit 1) (value "C_1u_0603") (footprint "sa800u-baseboard-hw-footprints:C_0603_1608Metric")
    )
    (path ""
      (reference "C76") (unit 1) (value "C_47u_0603") (footprint "sa800u-baseboard-hw-footprints:C_0603_1608Metric")
    )
    (path ""
      (reference "C77") (unit 1) (value "C_2u2_0603") (footprint "sa800u-baseboard-hw-footprints:C_0603_1608Metric")
    )
    (path ""
      (reference "C78") (unit 1) (value "C_47u_0603") (footprint "sa800u-baseboard-hw-footprints:C_0603_1608Metric")
    )
    (path ""
      (reference "C79") (unit 1) (value "C_100n_0402") (footprint "sa800u-baseboard-hw-footprints:C_0402_1005Metric")
    )
    (path ""
      (reference "C80") (unit 1) (value "C_100n_0402") (footprint "sa800u-baseboard-hw-footprints:C_0402_1005Metric")
    )
    (path ""
      (reference "C81") (unit 1) (value "C_100n_0402") (footprint "sa800u-baseboard-hw-footprints:C_0402_1005Metric")
    )
    (path ""
      (reference "C82") (unit 1) (value "C_100n_0402") (footprint "sa800u-baseboard-hw-footprints:C_0402_1005Metric")
    )
    (path ""
      (reference "C83") (unit 1) (value "C_100n_0402") (footprint "sa800u-baseboard-hw-footprints:C_0402_1005Metric")
    )
    (path ""
      (reference "C84") (unit 1) (value "C_100n_0402") (footprint "sa800u-baseboard-hw-footprints:C_0402_1005Metric")
    )
    (path ""
      (reference "C85") (unit 1) (value "C_100n_0402") (footprint "sa800u-baseboard-hw-footprints:C_0402_1005Metric")
    )
    (path ""
      (reference "C86") (unit 1) (value "C_100n_0402") (footprint "sa800u-baseboard-hw-footprints:C_0402_1005Metric")
    )
    (path ""
      (reference "C87") (unit 1) (value "C_100n_0402") (footprint "sa800u-baseboard-hw-footprints:C_0402_1005Metric")
    )
    (path ""
      (reference "C88") (unit 1) (value "C_100n_0402") (footprint "sa800u-baseboard-hw-footprints:C_0402_1005Metric")
    )
    (path ""
      (reference "C89") (unit 1) (value "C_47u_0603") (footprint "sa800u-baseboard-hw-footprints:C_0603_1608Metric")
    )
    (path ""
      (reference "C90") (unit 1) (value "C_100n_0402") (footprint "sa800u-baseboard-hw-footprints:C_0402_1005Metric")
    )
    (path ""
      (reference "C91") (unit 1) (value "C_100n_0402") (footprint "sa800u-baseboard-hw-footprints:C_0402_1005Metric")
    )
    (path ""
      (reference "C92") (unit 1) (value "C_100n_0402") (footprint "sa800u-baseboard-hw-footprints:C_0402_1005Metric")
    )
    (path ""
      (reference "C93") (unit 1) (value "C_100n_0402") (footprint "sa800u-baseboard-hw-footprints:C_0402_1005Metric")
    )
    (path ""
      (reference "C94") (unit 1) (value "C_100n_0402") (footprint "sa800u-baseboard-hw-footprints:C_0402_1005Metric")
    )
    (path ""
      (reference "C95") (unit 1) (value "C_100n_0402") (footprint "sa800u-baseboard-hw-footprints:C_0402_1005Metric")
    )
    (path ""
      (reference "C96") (unit 1) (value "C_47u_0603") (footprint "sa800u-baseboard-hw-footprints:C_0603_1608Metric")
    )
    (path ""
      (reference "C97") (unit 1) (value "C_100n_0402") (footprint "sa800u-baseboard-hw-footprints:C_0402_1005Metric")
    )
    (path ""
      (reference "C98") (unit 1) (value "C_100n_0402") (footprint "sa800u-baseboard-hw-footprints:C_0402_1005Metric")
    )
    (path ""
      (reference "C99") (unit 1) (value "C_100u_0805") (footprint "sa800u-baseboard-hw-footprints:C_0805_2012Metric")
    )
    (path ""
      (reference "C100") (unit 1) (value "C_100u_0805") (footprint "sa800u-baseboard-hw-footprints:C_0805_2012Metric")
    )
    (path ""
      (reference "C101") (unit 1) (value "C_100u_0805") (footprint "sa800u-baseboard-hw-footprints:C_0805_2012Metric")
    )
    (path ""
      (reference "C102") (unit 1) (value "C_100n_0402") (footprint "sa800u-baseboard-hw-footprints:C_0402_1005Metric")
    )
    (path ""
      (reference "C103") (unit 1) (value "C_33p_0402") (footprint "sa800u-baseboard-hw-footprints:C_0402_1005Metric")
    )
    (path ""
      (reference "C104") (unit 1) (value "C_10p_0402") (footprint "sa800u-baseboard-hw-footprints:C_0402_1005Metric")
    )
    (path ""
      (reference "C105") (unit 1) (value "C_4u7_0805") (footprint "sa800u-baseboard-hw-footprints:C_0805_2012Metric")
    )
    (path ""
      (reference "C106") (unit 1) (value "C_100n_0402") (footprint "sa800u-baseboard-hw-footprints:C_0402_1005Metric")
    )
    (path ""
      (reference "C107") (unit 1) (value "C_100n_0402") (footprint "sa800u-baseboard-hw-footprints:C_0402_1005Metric")
    )
    (path ""
      (reference "C108") (unit 1) (value "C_4u7_0805") (footprint "sa800u-baseboard-hw-footprints:C_0805_2012Metric")
    )
    (path ""
      (reference "C109") (unit 1) (value "C_100n_0402") (footprint "sa800u-baseboard-hw-footprints:C_0402_1005Metric")
    )
    (path ""
      (reference "C110") (unit 1) (value "C_100n_0402") (footprint "sa800u-baseboard-hw-footprints:C_0402_1005Metric")
    )
    (path ""
      (reference "C111") (unit 1) (value "C_1u_0402") (footprint "sa800u-baseboard-hw-footprints:C_0402_1005Metric")
    )
    (path ""
      (reference "C112") (unit 1) (value "C_1u_0402") (footprint "sa800u-baseboard-hw-footprints:C_0402_1005Metric")
    )
    (path ""
      (reference "C113") (unit 1) (value "C_1u_0402") (footprint "sa800u-baseboard-hw-footprints:C_0402_1005Metric")
    )
    (path ""
      (reference "C114") (unit 1) (value "C_1u_0402") (footprint "sa800u-baseboard-hw-footprints:C_0402_1005Metric")
    )
    (path ""
      (reference "C115") (unit 1) (value "C_100n_0402") (footprint "sa800u-baseboard-hw-footprints:C_0402_1005Metric")
    )
    (path ""
      (reference "C116") (unit 1) (value "C_100n_0402") (footprint "sa800u-baseboard-hw-footprints:C_0402_1005Metric")
    )
    (path ""
      (reference "C117") (unit 1) (value "C_100n_0402") (footprint "sa800u-baseboard-hw-footprints:C_0402_1005Metric")
    )
    (path ""
      (reference "C118") (unit 1) (value "C_10p_0402") (footprint "sa800u-baseboard-hw-footprints:C_0402_1005Metric")
    )
    (path ""
      (reference "C119") (unit 1) (value "C_2u2_0603") (footprint "sa800u-baseboard-hw-footprints:C_0603_1608Metric")
    )
    (path ""
      (reference "C120") (unit 1) (value "C_100n_0402") (footprint "sa800u-baseboard-hw-footprints:C_0402_1005Metric")
    )
    (path ""
      (reference "C121") (unit 1) (value "C_10u_25V_0603") (footprint "sa800u-baseboard-hw-footprints:C_0603_1608Metric")
    )
    (path ""
      (reference "C122") (unit 1) (value "C_10u_25V_0603") (footprint "sa800u-baseboard-hw-footprints:C_0603_1608Metric")
    )
    (path ""
      (reference "C123") (unit 1) (value "C_100n_0402") (footprint "sa800u-baseboard-hw-footprints:C_0402_1005Metric")
    )
    (path ""
      (reference "C124") (unit 1) (value "C_100n_0402") (footprint "sa800u-baseboard-hw-footprints:C_0402_1005Metric")
    )
    (path ""
      (reference "C125") (unit 1) (value "C_100n_0402") (footprint "sa800u-baseboard-hw-footprints:C_0402_1005Metric")
    )
    (path ""
      (reference "C126") (unit 1) (value "C_10u_25V_0603") (footprint "sa800u-baseboard-hw-footprints:C_0603_1608Metric")
    )
    (path ""
      (reference "C127") (unit 1) (value "C_10u_25V_0603") (footprint "sa800u-baseboard-hw-footprints:C_0603_1608Metric")
    )
    (path ""
      (reference "C128") (unit 1) (value "C_22u_0603") (footprint "sa800u-baseboard-hw-footprints:C_0603_1608Metric")
    )
    (path ""
      (reference "C129") (unit 1) (value "C_22u_0603") (footprint "sa800u-baseboard-hw-footprints:C_0603_1608Metric")
    )
    (path ""
      (reference "C130") (unit 1) (value "C_22u_0603") (footprint "sa800u-baseboard-hw-footprints:C_0603_1608Metric")
    )
    (path ""
      (reference "C131") (unit 1) (value "C_10u_25V_0603") (footprint "sa800u-baseboard-hw-footprints:C_0603_1608Metric")
    )
    (path ""
      (reference "C132") (unit 1) (value "C_100n_0402") (footprint "sa800u-baseboard-hw-footprints:C_0402_1005Metric")
    )
    (path ""
      (reference "C133") (unit 1) (value "C_100n_0402") (footprint "sa800u-baseboard-hw-footprints:C_0402_1005Metric")
    )
    (path ""
      (reference "C134") (unit 1) (value "C_100n_0402") (footprint "sa800u-baseboard-hw-footprints:C_0402_1005Metric")
    )
    (path ""
      (reference "C135") (unit 1) (value "C_22u_0603") (footprint "sa800u-baseboard-hw-footprints:C_0603_1608Metric")
    )
    (path ""
      (reference "C136") (unit 1) (value "C_22u_0603") (footprint "sa800u-baseboard-hw-footprints:C_0603_1608Metric")
    )
    (path ""
      (reference "C137") (unit 1) (value "C_22u_0603") (footprint "sa800u-baseboard-hw-footprints:C_0603_1608Metric")
    )
    (path ""
      (reference "C138") (unit 1) (value "C_100n_0402") (footprint "sa800u-baseboard-hw-footprints:C_0402_1005Metric")
    )
    (path ""
      (reference "C139") (unit 1) (value "C_22u_0603") (footprint "sa800u-baseboard-hw-footprints:C_0603_1608Metric")
    )
    (path ""
      (reference "C140") (unit 1) (value "C_22u_0603") (footprint "sa800u-baseboard-hw-footprints:C_0603_1608Metric")
    )
    (path ""
      (reference "C141") (unit 1) (value "C_22u_0603") (footprint "sa800u-baseboard-hw-footprints:C_0603_1608Metric")
    )
    (path ""
      (reference "C142") (unit 1) (value "C_22u_0603") (footprint "sa800u-baseboard-hw-footprints:C_0603_1608Metric")
    )
    (path ""
      (reference "C143") (unit 1) (value "C_22u_0603") (footprint "sa800u-baseboard-hw-footprints:C_0603_1608Metric")
    )
    (path ""
      (reference "C144") (unit 1) (value "C_100n_0805_100V") (footprint "sa800u-baseboard-hw-footprints:C_0805_2012Metric")
    )
    (path ""
      (reference "C145") (unit 1) (value "C_47u_ELEC_100V") (footprint "sa800u-baseboard-hw-footprints:C_Elec_10x10.5mm")
    )
    (path ""
      (reference "C146") (unit 1) (value "C_47u_ELEC_100V") (footprint "sa800u-baseboard-hw-footprints:C_Elec_10x10.5mm")
    )
    (path ""
      (reference "C147") (unit 1) (value "C_100u_0805") (footprint "sa800u-baseboard-hw-footprints:C_0805_2012Metric")
    )
    (path ""
      (reference "C148") (unit 1) (value "C_100u_0805") (footprint "sa800u-baseboard-hw-footprints:C_0805_2012Metric")
    )
    (path ""
      (reference "C149") (unit 1) (value "C_47u_0805") (footprint "sa800u-baseboard-hw-footprints:C_0805_2012Metric")
    )
    (path ""
      (reference "C150") (unit 1) (value "C_1u_0402") (footprint "sa800u-baseboard-hw-footprints:C_0402_1005Metric")
    )
    (path ""
      (reference "C151") (unit 1) (value "C_100n_0402") (footprint "sa800u-baseboard-hw-footprints:C_0402_1005Metric")
    )
    (path ""
      (reference "C152") (unit 1) (value "C_4u7_0603") (footprint "sa800u-baseboard-hw-footprints:C_0603_1608Metric")
    )
    (path ""
      (reference "C153") (unit 1) (value "C_1u_0603") (footprint "sa800u-baseboard-hw-footprints:C_0603_1608Metric")
    )
    (path ""
      (reference "C154") (unit 1) (value "C_1u_0402") (footprint "sa800u-baseboard-hw-footprints:C_0402_1005Metric")
    )
    (path ""
      (reference "C155") (unit 1) (value "C_100n_0402") (footprint "sa800u-baseboard-hw-footprints:C_0402_1005Metric")
    )
    (path ""
      (reference "C156") (unit 1) (value "C_1u_0402") (footprint "sa800u-baseboard-hw-footprints:C_0402_1005Metric")
    )
    (path ""
      (reference "C157") (unit 1) (value "C_1u_0402") (footprint "sa800u-baseboard-hw-footprints:C_0402_1005Metric")
    )
    (path ""
      (reference "D1") (unit 1) (value "1N4148WS") (footprint "sa800u-baseboard-hw-footprints:D_SOD-323F")
    )
    (path ""
      (reference "D2") (unit 1) (value "1N4148WS") (footprint "sa800u-baseboard-hw-footprints:D_SOD-323F")
    )
    (path ""
      (reference "D3") (unit 1) (value "PUSB3F96X_PASS") (footprint "sa800u-baseboard-hw-footprints:Nexperia_DFN-10_2.5x1mm_P0.5mm")
    )
    (path ""
      (reference "D4") (unit 1) (value "PUSB3F96X_PASS") (footprint "sa800u-baseboard-hw-footprints:Nexperia_DFN-10_2.5x1mm_P0.5mm")
    )
    (path ""
      (reference "D5") (unit 1) (value "PUSB3F96X_PASS") (footprint "sa800u-baseboard-hw-footprints:Nexperia_DFN-10_2.5x1mm_P0.5mm")
    )
    (path ""
      (reference "D6") (unit 1) (value "1N4148WS") (footprint "sa800u-baseboard-hw-footprints:D_SOD-323F")
    )
    (path ""
      (reference "D7") (unit 1) (value "PUSB3F96X_PASS") (footprint "sa800u-baseboard-hw-footprints:Nexperia_DFN-10_2.5x1mm_P0.5mm")
    )
    (path ""
      (reference "D8") (unit 1) (value "PUSB3F96X_PASS") (footprint "sa800u-baseboard-hw-footprints:Nexperia_DFN-10_2.5x1mm_P0.5mm")
    )
    (path ""
      (reference "D9") (unit 1) (value "PUSB3F96X_PASS") (footprint "sa800u-baseboard-hw-footprints:Nexperia_DFN-10_2.5x1mm_P0.5mm")
    )
    (path ""
      (reference "D10") (unit 1) (value "PUSB3F96X_PASS") (footprint "sa800u-baseboard-hw-footprints:Nexperia_DFN-10_2.5x1mm_P0.5mm")
    )
    (path ""
      (reference "D11") (unit 1) (value "PUSB3F96X_PASS") (footprint "sa800u-baseboard-hw-footprints:Nexperia_DFN-10_2.5x1mm_P0.5mm")
    )
    (path ""
      (reference "D12") (unit 1) (value "PUSB3F96X_PASS") (footprint "sa800u-baseboard-hw-footprints:Nexperia_DFN-10_2.5x1mm_P0.5mm")
    )
    (path ""
      (reference "D13") (unit 1) (value "STS321045B502") (footprint "sa800u-baseboard-hw-footprints:SOD-323")
    )
    (path ""
      (reference "D14") (unit 1) (value "KP-1608EC") (footprint "sa800u-baseboard-hw-footprints:LED_0603_1608Metric_G")
    )
    (path ""
      (reference "D15") (unit 1) (value "KP-1608EC") (footprint "sa800u-baseboard-hw-footprints:LED_0603_1608Metric_G")
    )
    (path ""
      (reference "D16") (unit 1) (value "KP-1608EC") (footprint "sa800u-baseboard-hw-footprints:LED_0603_1608Metric_G")
    )
    (path ""
      (reference "D17") (unit 1) (value "PESD2V5Y1BSFYL") (footprint "sa800u-baseboard-hw-footprints:D_0201_0603Metric")
    )
    (path ""
      (reference "D18") (unit 1) (value "PESD2V5Y1BSFYL") (footprint "sa800u-baseboard-hw-footprints:D_0201_0603Metric")
    )
    (path ""
      (reference "D19") (unit 1) (value "PESD2V5Y1BSFYL") (footprint "sa800u-baseboard-hw-footprints:D_0201_0603Metric")
    )
    (path ""
      (reference "D20") (unit 1) (value "PESD2V5Y1BSFYL") (footprint "sa800u-baseboard-hw-footprints:D_0201_0603Metric")
    )
    (path ""
      (reference "D21") (unit 1) (value "KP-1608EC") (footprint "sa800u-baseboard-hw-footprints:LED_0603_1608Metric_G")
    )
    (path ""
      (reference "D22") (unit 1) (value "PUSB3F96X_PASS") (footprint "sa800u-baseboard-hw-footprints:Nexperia_DFN-10_2.5x1mm_P0.5mm")
    )
    (path ""
      (reference "D23") (unit 1) (value "PUSB3F96X_PASS") (footprint "sa800u-baseboard-hw-footprints:Nexperia_DFN-10_2.5x1mm_P0.5mm")
    )
    (path ""
      (reference "D24") (unit 1) (value "KP-1608EC") (footprint "sa800u-baseboard-hw-footprints:LED_0603_1608Metric_G")
    )
    (path ""
      (reference "D25") (unit 1) (value "KP-1608EC") (footprint "sa800u-baseboard-hw-footprints:LED_0603_1608Metric_G")
    )
    (path ""
      (reference "D26") (unit 1) (value "KP-1608EC") (footprint "sa800u-baseboard-hw-footprints:LED_0603_1608Metric_G")
    )
    (path ""
      (reference "D27") (unit 1) (value "KP-1608EC") (footprint "sa800u-baseboard-hw-footprints:LED_0603_1608Metric_G")
    )
    (path ""
      (reference "D28") (unit 1) (value "KP-1608EC") (footprint "sa800u-baseboard-hw-footprints:LED_0603_1608Metric_G")
    )
    (path ""
      (reference "D29") (unit 1) (value "MB10S") (footprint "sa800u-baseboard-hw-footprints:SOIC-4_4.2x5.0mm_P5.7mm")
    )
    (path ""
      (reference "D30") (unit 1) (value "MB10S") (footprint "sa800u-baseboard-hw-footprints:SOIC-4_4.2x5.0mm_P5.7mm")
    )
    (path ""
      (reference "D31") (unit 1) (value "SMAJ58A-13-F") (footprint "sa800u-baseboard-hw-footprints:DO-214AC")
    )
    (path ""
      (reference "D32") (unit 1) (value "KP-1608EC") (footprint "sa800u-baseboard-hw-footprints:LED_0603_1608Metric_G")
    )
    (path ""
      (reference "D33") (unit 1) (value "PESD18VF1BSFYL") (footprint "sa800u-baseboard-hw-footprints:D_0201_0603Metric")
    )
    (path ""
      (reference "D34") (unit 1) (value "PESD18VF1BSFYL") (footprint "sa800u-baseboard-hw-footprints:D_0201_0603Metric")
    )
    (path ""
      (reference "D35") (unit 1) (value "PMEG6002EJ,115") (footprint "sa800u-baseboard-hw-footprints:D_SOD-323F")
    )
    (path ""
      (reference "D36") (unit 1) (value "ASMB-TTF0-0A20B") (footprint "sa800u-baseboard-hw-footprints:PLCC6_3.5x3.7mm")
    )
    (path ""
      (reference "D37") (unit 1) (value "PESD18VF1BSFYL") (footprint "sa800u-baseboard-hw-footprints:D_0201_0603Metric")
    )
    (path ""
      (reference "D38") (unit 1) (value "PMEG3050EP,115") (footprint "sa800u-baseboard-hw-footprints:Nexperia_SOD128")
    )
    (path ""
      (reference "FB1") (unit 1) (value "FB_120Z_3A_0603") (footprint "sa800u-baseboard-hw-footprints:FB_0603_1608Metric")
    )
    (path ""
      (reference "FB2") (unit 1) (value "FB_120Z_3A_0603") (footprint "sa800u-baseboard-hw-footprints:FB_0603_1608Metric")
    )
    (path ""
      (reference "FB3") (unit 1) (value "FB_220Z_1A_0603") (footprint "sa800u-baseboard-hw-footprints:FB_0603_1608Metric")
    )
    (path ""
      (reference "FB4") (unit 1) (value "FB_220Z_2A_0805") (footprint "sa800u-baseboard-hw-footprints:FB_0805_2012Metric")
    )
    (path ""
      (reference "FB5") (unit 1) (value "FB_220Z_2A_0805") (footprint "sa800u-baseboard-hw-footprints:FB_0805_2012Metric")
    )
    (path ""
      (reference "IC1") (unit 1) (value "TPS7A0518P_SOT23-5") (footprint "sa800u-baseboard-hw-footprints:SOT-23-5")
    )
    (path ""
      (reference "IC2") (unit 1) (value "TPS2378DDA") (footprint "sa800u-baseboard-hw-footprints:SOIC-8-1EP_3.9x4.9x1.75mm_P1.27mm")
    )
    (path ""
      (reference "J1") (unit 1) (value "Bus_RJ45_5-2337992-8") (footprint "sa800u-baseboard-hw-footprints:RJ45_5-2337992-8_Horizontal")
    )
    (path ""
      (reference "J2") (unit 1) (value "HDMI_Micro-D_46756-1001") (footprint "sa800u-baseboard-hw-footprints:HDMI_Micro-D_Molex_46765-1x01")
    )
    (path ""
      (reference "J3") (unit 1) (value "12401598E4_2A") (footprint "sa800u-baseboard-hw-footprints:USB-C_12401610E4_2A")
    )
    (path ""
      (reference "J4") (unit 1) (value "12401598E4_2A") (footprint "sa800u-baseboard-hw-footprints:USB-C_12401610E4_2A")
    )
    (path ""
      (reference "J5") (unit 1) (value "12401598E4_2A") (footprint "sa800u-baseboard-hw-footprints:USB-C_12401610E4_2A")
    )
    (path ""
      (reference "J6") (unit 1) (value "F52R-1A7H1-11020") (footprint "sa800u-baseboard-hw-footprints:F52R-1A7H1-11020")
    )
    (path ""
      (reference "J7") (unit 1) (value "Conn_FFC_WE_68715014522_TWO-SIDES") (footprint "sa800u-baseboard-hw-footprints:Conn_FFC_WE_68715014x22_ALT")
    )
    (path ""
      (reference "J8") (unit 1) (value "DM3AT-SF-PEJM5") (footprint "sa800u-baseboard-hw-footprints:MicroSD_DM3AT-SF-PEJM5")
    )
    (path ""
      (reference "J9") (unit 1) (value "BM04B-SRSS-TB-LF-SN") (footprint "sa800u-baseboard-hw-footprints:BM04B-SRSS-TB-LF-SN")
    )
    (path ""
      (reference "J10") (unit 1) (value "Conn_Molex_NanoFit_1053131202") (footprint "sa800u-baseboard-hw-footprints:Conn_Molex_NanoFit_1053131202")
    )
    (path ""
      (reference "J11") (unit 1) (value "12401598E4_2A") (footprint "sa800u-baseboard-hw-footprints:USB-C_12401610E4_2A")
    )
    (path ""
      (reference "L1") (unit 1) (value "L_350n_1.4A_0603") (footprint "sa800u-baseboard-hw-footprints:L_0603_1608Metric")
    )
    (path ""
      (reference "L2") (unit 1) (value "L_350n_1.4A_0603") (footprint "sa800u-baseboard-hw-footprints:L_0603_1608Metric")
    )
    (path ""
      (reference "L3") (unit 1) (value "L_350n_1.4A_0603") (footprint "sa800u-baseboard-hw-footprints:L_0603_1608Metric")
    )
    (path ""
      (reference "L4") (unit 1) (value "L_350n_1.4A_0603") (footprint "sa800u-baseboard-hw-footprints:L_0603_1608Metric")
    )
    (path ""
      (reference "L5") (unit 1) (value "L_350n_1.4A_0603") (footprint "sa800u-baseboard-hw-footprints:L_0603_1608Metric")
    )
    (path ""
      (reference "L6") (unit 1) (value "L_350n_1.4A_0603") (footprint "sa800u-baseboard-hw-footprints:L_0603_1608Metric")
    )
    (path ""
      (reference "L7") (unit 1) (value "NFP0QHB242HS2D") (footprint "sa800u-baseboard-hw-footprints:L_Murata_025020_0605Metric")
    )
    (path ""
      (reference "L8") (unit 1) (value "NFP0QHB242HS2D") (footprint "sa800u-baseboard-hw-footprints:L_Murata_025020_0605Metric")
    )
    (path ""
      (reference "L9") (unit 1) (value "NFP0QHB242HS2D") (footprint "sa800u-baseboard-hw-footprints:L_Murata_025020_0605Metric")
    )
    (path ""
      (reference "L10") (unit 1) (value "NFP0QHB242HS2D") (footprint "sa800u-baseboard-hw-footprints:L_Murata_025020_0605Metric")
    )
    (path ""
      (reference "L11") (unit 1) (value "NFP0QHB242HS2D") (footprint "sa800u-baseboard-hw-footprints:L_Murata_025020_0605Metric")
    )
    (path ""
      (reference "L12") (unit 1) (value "NFP0QHB242HS2D") (footprint "sa800u-baseboard-hw-footprints:L_Murata_025020_0605Metric")
    )
    (path ""
      (reference "L13") (unit 1) (value "NFP0QHB242HS2D") (footprint "sa800u-baseboard-hw-footprints:L_Murata_025020_0605Metric")
    )
    (path ""
      (reference "L14") (unit 1) (value "NFP0QHB242HS2D") (footprint "sa800u-baseboard-hw-footprints:L_Murata_025020_0605Metric")
    )
    (path ""
      (reference "L15") (unit 1) (value "NFP0QHB242HS2D") (footprint "sa800u-baseboard-hw-footprints:L_Murata_025020_0605Metric")
    )
    (path ""
      (reference "L16") (unit 1) (value "NFP0QHB242HS2D") (footprint "sa800u-baseboard-hw-footprints:L_Murata_025020_0605Metric")
    )
    (path ""
      (reference "L17") (unit 1) (value "NFP0QHB242HS2D") (footprint "sa800u-baseboard-hw-footprints:L_Murata_025020_0605Metric")
    )
    (path ""
      (reference "L18") (unit 1) (value "NFP0QHB242HS2D") (footprint "sa800u-baseboard-hw-footprints:L_Murata_025020_0605Metric")
    )
    (path ""
      (reference "L19") (unit 1) (value "NFP0QHB242HS2D") (footprint "sa800u-baseboard-hw-footprints:L_Murata_025020_0605Metric")
    )
    (path ""
      (reference "L20") (unit 1) (value "NFP0QHB242HS2D") (footprint "sa800u-baseboard-hw-footprints:L_Murata_025020_0605Metric")
    )
    (path ""
      (reference "L21") (unit 1) (value "NFP0QHB242HS2D") (footprint "sa800u-baseboard-hw-footprints:L_Murata_025020_0605Metric")
    )
    (path ""
      (reference "L22") (unit 1) (value "NFP0QHB242HS2D") (footprint "sa800u-baseboard-hw-footprints:L_Murata_025020_0605Metric")
    )
    (path ""
      (reference "L23") (unit 1) (value "NFP0QHB242HS2D") (footprint "sa800u-baseboard-hw-footprints:L_Murata_025020_0605Metric")
    )
    (path ""
      (reference "L24") (unit 1) (value "NFP0QHB242HS2D") (footprint "sa800u-baseboard-hw-footprints:L_Murata_025020_0605Metric")
    )
    (path ""
      (reference "L25") (unit 1) (value "NFP0QHB242HS2D") (footprint "sa800u-baseboard-hw-footprints:L_Murata_025020_0605Metric")
    )
    (path ""
      (reference "L26") (unit 1) (value "L_2u2_6.1A_XEL4030") (footprint "sa800u-baseboard-hw-footprints:L_Coilcraft_XEL4030")
    )
    (path ""
      (reference "L27") (unit 1) (value "L_2u2_6.1A_XEL4030") (footprint "sa800u-baseboard-hw-footprints:L_Coilcraft_XEL4030")
    )
    (path ""
      (reference "L28") (unit 1) (value "L_2u2_6.1A_XEL4030") (footprint "sa800u-baseboard-hw-footprints:L_Coilcraft_XEL4030")
    )
    (path ""
      (reference "L29") (unit 1) (value "L_2u2_6.1A_XEL4030") (footprint "sa800u-baseboard-hw-footprints:L_Coilcraft_XEL4030")
    )
    (path ""
      (reference "M2") (unit 1) (value "Mech_M2_2280_H4mm") (footprint "sa800u-baseboard-hw-footprints:Mech_M2_2280_H4mm")
    )
    (path ""
      (reference "PS1") (unit 1) (value "PDQE30-Q48-S5-D") (footprint "sa800u-baseboard-hw-footprints:CONV_PDQE30-Q48-S5-D")
    )
    (path ""
      (reference "Q1") (unit 1) (value "BSS138PW") (footprint "sa800u-baseboard-hw-footprints:SC70-3")
    )
    (path ""
      (reference "Q2") (unit 1) (value "BSS138PW") (footprint "sa800u-baseboard-hw-footprints:SC70-3")
    )
    (path ""
      (reference "Q3") (unit 1) (value "BSS138PW") (footprint "sa800u-baseboard-hw-footprints:SC70-3")
    )
    (path ""
      (reference "Q4") (unit 1) (value "BSS138PW") (footprint "sa800u-baseboard-hw-footprints:SC70-3")
    )
    (path ""
      (reference "Q5") (unit 1) (value "BSS138PW") (footprint "sa800u-baseboard-hw-footprints:SC70-3")
    )
    (path ""
      (reference "Q6") (unit 1) (value "BSS138PW") (footprint "sa800u-baseboard-hw-footprints:SC70-3")
    )
    (path ""
      (reference "Q7") (unit 1) (value "BSS138PW") (footprint "sa800u-baseboard-hw-footprints:SC70-3")
    )
    (path ""
      (reference "Q8") (unit 1) (value "BSS84") (footprint "sa800u-baseboard-hw-footprints:SOT-23-3")
    )
    (path ""
      (reference "Q9") (unit 1) (value "Si7223DN") (footprint "sa800u-baseboard-hw-footprints:PowerPak-1212")
    )
    (path ""
      (reference "Q10") (unit 1) (value "BSS84") (footprint "sa800u-baseboard-hw-footprints:SOT-23-3")
    )
    (path ""
      (reference "Q11") (unit 1) (value "Si7223DN") (footprint "sa800u-baseboard-hw-footprints:PowerPak-1212")
    )
    (path ""
      (reference "Q12") (unit 1) (value "Si7223DN") (footprint "sa800u-baseboard-hw-footprints:PowerPak-1212")
    )
    (path ""
      (reference "Q13") (unit 1) (value "BSS84") (footprint "sa800u-baseboard-hw-footprints:SOT-23-3")
    )
    (path ""
      (reference "Q14") (unit 1) (value "BSS84") (footprint "sa800u-baseboard-hw-footprints:SOT-23-3")
    )
    (path ""
      (reference "Q15") (unit 1) (value "BSS84PH6327XTSA2") (footprint "sa800u-baseboard-hw-footprints:SOT-23-3")
    )
    (path ""
      (reference "Q16") (unit 1) (value "SQS401EN-T1_BE3") (footprint "sa800u-baseboard-hw-footprints:Vishay_PowerPAK_1212-8_Single")
    )
    (path ""
      (reference "Q17") (unit 1) (value "SQS401EN-T1_BE3") (footprint "sa800u-baseboard-hw-footprints:Vishay_PowerPAK_1212-8_Single")
    )
    (path ""
      (reference "R1") (unit 1) (value "R_0R_0402") (footprint "sa800u-baseboard-hw-footprints:R_0402_1005Metric")
    )
    (path ""
      (reference "R2") (unit 1) (value "R_0R_0402") (footprint "sa800u-baseboard-hw-footprints:R_0402_1005Metric")
    )
    (path ""
      (reference "R3") (unit 1) (value "R_0R_0402") (footprint "sa800u-baseboard-hw-footprints:R_0402_1005Metric")
    )
    (path ""
      (reference "R4") (unit 1) (value "R_0R_0402") (footprint "sa800u-baseboard-hw-footprints:R_0402_1005Metric")
    )
    (path ""
      (reference "R5") (unit 1) (value "R_1M_0402") (footprint "sa800u-baseboard-hw-footprints:R_0402_1005Metric")
    )
    (path ""
      (reference "R6") (unit 1) (value "R_10k_0402") (footprint "sa800u-baseboard-hw-footprints:R_0402_1005Metric")
    )
    (path ""
      (reference "R7") (unit 1) (value "R_1k_0402") (footprint "sa800u-baseboard-hw-footprints:R_0402_1005Metric")
    )
    (path ""
      (reference "R8") (unit 1) (value "R_10k_0402") (footprint "sa800u-baseboard-hw-footprints:R_0402_1005Metric")
    )
    (path ""
      (reference "R9") (unit 1) (value "R_1k_0402") (footprint "sa800u-baseboard-hw-footprints:R_0402_1005Metric")
    )
    (path ""
      (reference "R10") (unit 1) (value "R_15k_0603") (footprint "sa800u-baseboard-hw-footprints:R_0603_1608Metric")
    )
    (path ""
      (reference "R11") (unit 1) (value "R_2k49_0402") (footprint "sa800u-baseboard-hw-footprints:R_0402_1005Metric")
    )
    (path ""
      (reference "R12") (unit 1) (value "R_0R_0402") (footprint "sa800u-baseboard-hw-footprints:R_0402_1005Metric")
    )
    (path ""
      (reference "R13") (unit 1) (value "R_470R_0402") (footprint "sa800u-baseboard-hw-footprints:R_0402_1005Metric")
    )
    (path ""
      (reference "R14") (unit 1) (value "R_470R_0402") (footprint "sa800u-baseboard-hw-footprints:R_0402_1005Metric")
    )
    (path ""
      (reference "R15") (unit 1) (value "R_1k_0402") (footprint "sa800u-baseboard-hw-footprints:R_0402_1005Metric")
    )
    (path ""
      (reference "R16") (unit 1) (value "R_0R_0402") (footprint "sa800u-baseboard-hw-footprints:R_0402_1005Metric")
    )
    (path ""
      (reference "R17") (unit 1) (value "R_10k_0402") (footprint "sa800u-baseboard-hw-footprints:R_0402_1005Metric")
    )
    (path ""
      (reference "R18") (unit 1) (value "R_4k7_0402") (footprint "sa800u-baseboard-hw-footprints:R_0402_1005Metric")
    )
    (path ""
      (reference "R19") (unit 1) (value "R_4k7_0402") (footprint "sa800u-baseboard-hw-footprints:R_0402_1005Metric")
    )
    (path ""
      (reference "R20") (unit 1) (value "R_4k7_0402") (footprint "sa800u-baseboard-hw-footprints:R_0402_1005Metric")
    )
    (path ""
      (reference "R21") (unit 1) (value "R_1M_0402") (footprint "sa800u-baseboard-hw-footprints:R_0402_1005Metric")
    )
    (path ""
      (reference "R22") (unit 1) (value "R_7k68_0402") (footprint "sa800u-baseboard-hw-footprints:R_0402_1005Metric")
    )
    (path ""
      (reference "R23") (unit 1) (value "R_4k7_0402") (footprint "sa800u-baseboard-hw-footprints:R_0402_1005Metric")
    )
    (path ""
      (reference "R24") (unit 1) (value "R_4k7_0402") (footprint "sa800u-baseboard-hw-footprints:R_0402_1005Metric")
    )
    (path ""
      (reference "R25") (unit 1) (value "R_4k7_0402") (footprint "sa800u-baseboard-hw-footprints:R_0402_1005Metric")
    )
    (path ""
      (reference "R26") (unit 1) (value "R_4k7_0402") (footprint "sa800u-baseboard-hw-footprints:R_0402_1005Metric")
    )
    (path ""
      (reference "R27") (unit 1) (value "R_20k_0402") (footprint "sa800u-baseboard-hw-footprints:R_0402_1005Metric")
    )
    (path ""
      (reference "R28") (unit 1) (value "R_2k2_0402") (footprint "sa800u-baseboard-hw-footprints:R_0402_1005Metric")
    )
    (path ""
      (reference "R29") (unit 1) (value "R_10k_0402") (footprint "sa800u-baseboard-hw-footprints:R_0402_1005Metric")
    )
    (path ""
      (reference "R30") (unit 1) (value "R_0R_0402") (footprint "sa800u-baseboard-hw-footprints:R_0402_1005Metric")
    )
    (path ""
      (reference "R31") (unit 1) (value "R_0R_0402") (footprint "sa800u-baseboard-hw-footprints:R_0402_1005Metric")
    )
    (path ""
      (reference "R32") (unit 1) (value "R_2k2_0402") (footprint "sa800u-baseboard-hw-footprints:R_0402_1005Metric")
    )
    (path ""
      (reference "R33") (unit 1) (value "R_27k_0402") (footprint "sa800u-baseboard-hw-footprints:R_0402_1005Metric")
    )
    (path ""
      (reference "R34") (unit 1) (value "R_2k_0402") (footprint "sa800u-baseboard-hw-footprints:R_0402_1005Metric")
    )
    (path ""
      (reference "R35") (unit 1) (value "R_50R_0402") (footprint "sa800u-baseboard-hw-footprints:R_0402_1005Metric")
    )
    (path ""
      (reference "R36") (unit 1) (value "R_2k_0402") (footprint "sa800u-baseboard-hw-footprints:R_0402_1005Metric")
    )
    (path ""
      (reference "R37") (unit 1) (value "R_50R_0402") (footprint "sa800u-baseboard-hw-footprints:R_0402_1005Metric")
    )
    (path ""
      (reference "R38") (unit 1) (value "R_50R_0402") (footprint "sa800u-baseboard-hw-footprints:R_0402_1005Metric")
    )
    (path ""
      (reference "R39") (unit 1) (value "R_50R_0402") (footprint "sa800u-baseboard-hw-footprints:R_0402_1005Metric")
    )
    (path ""
      (reference "R40") (unit 1) (value "R_50R_0402") (footprint "sa800u-baseboard-hw-footprints:R_0402_1005Metric")
    )
    (path ""
      (reference "R41") (unit 1) (value "R_10k_0402") (footprint "sa800u-baseboard-hw-footprints:R_0402_1005Metric")
    )
    (path ""
      (reference "R42") (unit 1) (value "R_50R_0402") (footprint "sa800u-baseboard-hw-footprints:R_0402_1005Metric")
    )
    (path ""
      (reference "R43") (unit 1) (value "R_20k_0402") (footprint "sa800u-baseboard-hw-footprints:R_0402_1005Metric")
    )
    (path ""
      (reference "R44") (unit 1) (value "R_2k_0402") (footprint "sa800u-baseboard-hw-footprints:R_0402_1005Metric")
    )
    (path ""
      (reference "R45") (unit 1) (value "R_50R_0402") (footprint "sa800u-baseboard-hw-footprints:R_0402_1005Metric")
    )
    (path ""
      (reference "R46") (unit 1) (value "R_2k_0402") (footprint "sa800u-baseboard-hw-footprints:R_0402_1005Metric")
    )
    (path ""
      (reference "R47") (unit 1) (value "R_50R_0402") (footprint "sa800u-baseboard-hw-footprints:R_0402_1005Metric")
    )
    (path ""
      (reference "R48") (unit 1) (value "R_510R_0402") (footprint "sa800u-baseboard-hw-footprints:R_0402_1005Metric")
    )
    (path ""
      (reference "R49") (unit 1) (value "R_510R_0402") (footprint "sa800u-baseboard-hw-footprints:R_0402_1005Metric")
    )
    (path ""
      (reference "R50") (unit 1) (value "R_10k_0402") (footprint "sa800u-baseboard-hw-footprints:R_0402_1005Metric")
    )
    (path ""
      (reference "R51") (unit 1) (value "R_510R_0402") (footprint "sa800u-baseboard-hw-footprints:R_0402_1005Metric")
    )
    (path ""
      (reference "R52") (unit 1) (value "R_510R_0402") (footprint "sa800u-baseboard-hw-footprints:R_0402_1005Metric")
    )
    (path ""
      (reference "R53") (unit 1) (value "R_510R_0402") (footprint "sa800u-baseboard-hw-footprints:R_0402_1005Metric")
    )
    (path ""
      (reference "R54") (unit 1) (value "R_510R_0402") (footprint "sa800u-baseboard-hw-footprints:R_0402_1005Metric")
    )
    (path ""
      (reference "R55") (unit 1) (value "R_510R_0402") (footprint "sa800u-baseboard-hw-footprints:R_0402_1005Metric")
    )
    (path ""
      (reference "R56") (unit 1) (value "R_510R_0402") (footprint "sa800u-baseboard-hw-footprints:R_0402_1005Metric")
    )
    (path ""
      (reference "R57") (unit 1) (value "R_100k_0402") (footprint "sa800u-baseboard-hw-footprints:R_0402_1005Metric")
    )
    (path ""
      (reference "R58") (unit 1) (value "R_100k_0402") (footprint "sa800u-baseboard-hw-footprints:R_0402_1005Metric")
    )
    (path ""
      (reference "R59") (unit 1) (value "R_100k_0.5%_0402") (footprint "sa800u-baseboard-hw-footprints:R_0402_1005Metric")
    )
    (path ""
      (reference "R60") (unit 1) (value "R_100k_0402") (footprint "sa800u-baseboard-hw-footprints:R_0402_1005Metric")
    )
    (path ""
      (reference "R61") (unit 1) (value "R_100k_0402") (footprint "sa800u-baseboard-hw-footprints:R_0402_1005Metric")
    )
    (path ""
      (reference "R62") (unit 1) (value "R_2k2_0402") (footprint "sa800u-baseboard-hw-footprints:R_0402_1005Metric")
    )
    (path ""
      (reference "R63") (unit 1) (value "R_100k_0402") (footprint "sa800u-baseboard-hw-footprints:R_0402_1005Metric")
    )
    (path ""
      (reference "R64") (unit 1) (value "R_200k_0402") (footprint "sa800u-baseboard-hw-footprints:R_0402_1005Metric")
    )
    (path ""
      (reference "R65") (unit 1) (value "R_2k_0402") (footprint "sa800u-baseboard-hw-footprints:R_0402_1005Metric")
    )
    (path ""
      (reference "R66") (unit 1) (value "R_2k_0402") (footprint "sa800u-baseboard-hw-footprints:R_0402_1005Metric")
    )
    (path ""
      (reference "R67") (unit 1) (value "R_2k_0402") (footprint "sa800u-baseboard-hw-footprints:R_0402_1005Metric")
    )
    (path ""
      (reference "R68") (unit 1) (value "R_2k_0402") (footprint "sa800u-baseboard-hw-footprints:R_0402_1005Metric")
    )
    (path ""
      (reference "R69") (unit 1) (value "R_1k_0402") (footprint "sa800u-baseboard-hw-footprints:R_0402_1005Metric")
    )
    (path ""
      (reference "R70") (unit 1) (value "R_47k_0402") (footprint "sa800u-baseboard-hw-footprints:R_0402_1005Metric")
    )
    (path ""
      (reference "R71") (unit 1) (value "R_4k7_0402") (footprint "sa800u-baseboard-hw-footprints:R_0402_1005Metric")
    )
    (path ""
      (reference "R72") (unit 1) (value "R_4k7_0402") (footprint "sa800u-baseboard-hw-footprints:R_0402_1005Metric")
    )
    (path ""
      (reference "R73") (unit 1) (value "R_1k_0402") (footprint "sa800u-baseboard-hw-footprints:R_0402_1005Metric")
    )
    (path ""
      (reference "R74") (unit 1) (value "R_1k_0402") (footprint "sa800u-baseboard-hw-footprints:R_0402_1005Metric")
    )
    (path ""
      (reference "R75") (unit 1) (value "R_1k_0402") (footprint "sa800u-baseboard-hw-footprints:R_0402_1005Metric")
    )
    (path ""
      (reference "R76") (unit 1) (value "R_1k_0402") (footprint "sa800u-baseboard-hw-footprints:R_0402_1005Metric")
    )
    (path ""
      (reference "R77") (unit 1) (value "R_10k_0402") (footprint "sa800u-baseboard-hw-footprints:R_0402_1005Metric")
    )
    (path ""
      (reference "R78") (unit 1) (value "R_10k_0402") (footprint "sa800u-baseboard-hw-footprints:R_0402_1005Metric")
    )
    (path ""
      (reference "R79") (unit 1) (value "R_10k_0402") (footprint "sa800u-baseboard-hw-footprints:R_0402_1005Metric")
    )
    (path ""
      (reference "R80") (unit 1) (value "R_2k_0402") (footprint "sa800u-baseboard-hw-footprints:R_0402_1005Metric")
    )
    (path ""
      (reference "R81") (unit 1) (value "R_2k_0402") (footprint "sa800u-baseboard-hw-footprints:R_0402_1005Metric")
    )
    (path ""
      (reference "R82") (unit 1) (value "R_2k_0402") (footprint "sa800u-baseboard-hw-footprints:R_0402_1005Metric")
    )
    (path ""
      (reference "R83") (unit 1) (value "R_2k_0402") (footprint "sa800u-baseboard-hw-footprints:R_0402_1005Metric")
    )
    (path ""
      (reference "R84") (unit 1) (value "R_0R_0603") (footprint "sa800u-baseboard-hw-footprints:R_0603_1608Metric")
    )
    (path ""
      (reference "R85") (unit 1) (value "R_0R_0603") (footprint "sa800u-baseboard-hw-footprints:R_0603_1608Metric")
    )
    (path ""
      (reference "R86") (unit 1) (value "R_2k_0402") (footprint "sa800u-baseboard-hw-footprints:R_0402_1005Metric")
    )
    (path ""
      (reference "R87") (unit 1) (value "R_2k_0402") (footprint "sa800u-baseboard-hw-footprints:R_0402_1005Metric")
    )
    (path ""
      (reference "R88") (unit 1) (value "R_2k_0402") (footprint "sa800u-baseboard-hw-footprints:R_0402_1005Metric")
    )
    (path ""
      (reference "R89") (unit 1) (value "R_2k_0402") (footprint "sa800u-baseboard-hw-footprints:R_0402_1005Metric")
    )
    (path ""
      (reference "R90") (unit 1) (value "R_10k_0402") (footprint "sa800u-baseboard-hw-footprints:R_0402_1005Metric")
    )
    (path ""
      (reference "R91") (unit 1) (value "R_10k_0402") (footprint "sa800u-baseboard-hw-footprints:R_0402_1005Metric")
    )
    (path ""
      (reference "R92") (unit 1) (value "R_220R_0402") (footprint "sa800u-baseboard-hw-footprints:R_0402_1005Metric")
    )
    (path ""
      (reference "R93") (unit 1) (value "R_10k_0402") (footprint "sa800u-baseboard-hw-footprints:R_0402_1005Metric")
    )
    (path ""
      (reference "R94") (unit 1) (value "R_100k_0402") (footprint "sa800u-baseboard-hw-footprints:R_0402_1005Metric")
    )
    (path ""
      (reference "R95") (unit 1) (value "R_1k_0402") (footprint "sa800u-baseboard-hw-footprints:R_0402_1005Metric")
    )
    (path ""
      (reference "R96") (unit 1) (value "R_33R_0402") (footprint "sa800u-baseboard-hw-footprints:R_0402_1005Metric")
    )
    (path ""
      (reference "R97") (unit 1) (value "R_33R_0402") (footprint "sa800u-baseboard-hw-footprints:R_0402_1005Metric")
    )
    (path ""
      (reference "R98") (unit 1) (value "R_33R_0402") (footprint "sa800u-baseboard-hw-footprints:R_0402_1005Metric")
    )
    (path ""
      (reference "R99") (unit 1) (value "R_0R_0402") (footprint "sa800u-baseboard-hw-footprints:R_0402_1005Metric")
    )
    (path ""
      (reference "R100") (unit 1) (value "R_33R_0402") (footprint "sa800u-baseboard-hw-footprints:R_0402_1005Metric")
    )
    (path ""
      (reference "R101") (unit 1) (value "R_33R_0402") (footprint "sa800u-baseboard-hw-footprints:R_0402_1005Metric")
    )
    (path ""
      (reference "R102") (unit 1) (value "R_33R_0402") (footprint "sa800u-baseboard-hw-footprints:R_0402_1005Metric")
    )
    (path ""
      (reference "R103") (unit 1) (value "R_2k_0402") (footprint "sa800u-baseboard-hw-footprints:R_0402_1005Metric")
    )
    (path ""
      (reference "R104") (unit 1) (value "R_2k_0402") (footprint "sa800u-baseboard-hw-footprints:R_0402_1005Metric")
    )
    (path ""
      (reference "R105") (unit 1) (value "R_200k_0402") (footprint "sa800u-baseboard-hw-footprints:R_0402_1005Metric")
    )
    (path ""
      (reference "R106") (unit 1) (value "R_39k_0402") (footprint "sa800u-baseboard-hw-footprints:R_0402_1005Metric")
    )
    (path ""
      (reference "R107") (unit 1) (value "R_13k7_0402") (footprint "sa800u-baseboard-hw-footprints:R_0402_1005Metric")
    )
    (path ""
      (reference "R108") (unit 1) (value "R_200k_0402") (footprint "sa800u-baseboard-hw-footprints:R_0402_1005Metric")
    )
    (path ""
      (reference "R109") (unit 1) (value "R_39k_0402") (footprint "sa800u-baseboard-hw-footprints:R_0402_1005Metric")
    )
    (path ""
      (reference "R110") (unit 1) (value "R_13k7_0402") (footprint "sa800u-baseboard-hw-footprints:R_0402_1005Metric")
    )
    (path ""
      (reference "R111") (unit 1) (value "R_10k_0402") (footprint "sa800u-baseboard-hw-footprints:R_0402_1005Metric")
    )
    (path ""
      (reference "R112") (unit 1) (value "R_200k_0402") (footprint "sa800u-baseboard-hw-footprints:R_0402_1005Metric")
    )
    (path ""
      (reference "R113") (unit 1) (value "R_39k_0402") (footprint "sa800u-baseboard-hw-footprints:R_0402_1005Metric")
    )
    (path ""
      (reference "R114") (unit 1) (value "R_13k7_0402") (footprint "sa800u-baseboard-hw-footprints:R_0402_1005Metric")
    )
    (path ""
      (reference "R115") (unit 1) (value "R_10k_0402") (footprint "sa800u-baseboard-hw-footprints:R_0402_1005Metric")
    )
    (path ""
      (reference "R116") (unit 1) (value "R_10k_0402") (footprint "sa800u-baseboard-hw-footprints:R_0402_1005Metric")
    )
    (path ""
      (reference "R117") (unit 1) (value "R_255k_0402") (footprint "sa800u-baseboard-hw-footprints:R_0402_1005Metric")
    )
    (path ""
      (reference "R118") (unit 1) (value "R_1M_0402") (footprint "sa800u-baseboard-hw-footprints:R_0402_1005Metric")
    )
    (path ""
      (reference "R119") (unit 1) (value "R_1M_0402") (footprint "sa800u-baseboard-hw-footprints:R_0402_1005Metric")
    )
    (path ""
      (reference "R120") (unit 1) (value "R_1M_0402") (footprint "sa800u-baseboard-hw-footprints:R_0402_1005Metric")
    )
    (path ""
      (reference "R121") (unit 1) (value "R_10k_0402") (footprint "sa800u-baseboard-hw-footprints:R_0402_1005Metric")
    )
    (path ""
      (reference "R122") (unit 1) (value "R_10k_0402") (footprint "sa800u-baseboard-hw-footprints:R_0402_1005Metric")
    )
    (path ""
      (reference "R123") (unit 1) (value "R_7k5_0402") (footprint "sa800u-baseboard-hw-footprints:R_0402_1005Metric")
    )
    (path ""
      (reference "R124") (unit 1) (value "R_2k2_0402") (footprint "sa800u-baseboard-hw-footprints:R_0402_1005Metric")
    )
    (path ""
      (reference "R125") (unit 1) (value "R_2k2_0402") (footprint "sa800u-baseboard-hw-footprints:R_0402_1005Metric")
    )
    (path ""
      (reference "R126") (unit 1) (value "R_1k_0402") (footprint "sa800u-baseboard-hw-footprints:R_0402_1005Metric")
    )
    (path ""
      (reference "R127") (unit 1) (value "R_10k_0402") (footprint "sa800u-baseboard-hw-footprints:R_0402_1005Metric")
    )
    (path ""
      (reference "R128") (unit 1) (value "R_10k_0402") (footprint "sa800u-baseboard-hw-footprints:R_0402_1005Metric")
    )
    (path ""
      (reference "R129") (unit 1) (value "R_25k5_0402") (footprint "sa800u-baseboard-hw-footprints:R_0402_1005Metric")
    )
    (path ""
      (reference "R130") (unit 1) (value "R_10k_0402") (footprint "sa800u-baseboard-hw-footprints:R_0402_1005Metric")
    )
    (path ""
      (reference "R131") (unit 1) (value "R_10k_0402") (footprint "sa800u-baseboard-hw-footprints:R_0402_1005Metric")
    )
    (path ""
      (reference "R132") (unit 1) (value "R_10k_0402") (footprint "sa800u-baseboard-hw-footprints:R_0402_1005Metric")
    )
    (path ""
      (reference "R133") (unit 1) (value "R_10k_0402") (footprint "sa800u-baseboard-hw-footprints:R_0402_1005Metric")
    )
    (path ""
      (reference "R134") (unit 1) (value "R_10k_0402") (footprint "sa800u-baseboard-hw-footprints:R_0402_1005Metric")
    )
    (path ""
      (reference "R135") (unit 1) (value "R_75k_0402") (footprint "sa800u-baseboard-hw-footprints:R_0402_1005Metric")
    )
    (path ""
      (reference "R136") (unit 1) (value "R_20k_0402") (footprint "sa800u-baseboard-hw-footprints:R_0402_1005Metric")
    )
    (path ""
      (reference "R137") (unit 1) (value "R_31k6_0402") (footprint "sa800u-baseboard-hw-footprints:R_0402_1005Metric")
    )
    (path ""
      (reference "R138") (unit 1) (value "R_10k_0402") (footprint "sa800u-baseboard-hw-footprints:R_0402_1005Metric")
    )
    (path ""
      (reference "R139") (unit 1) (value "R_10k_0402") (footprint "sa800u-baseboard-hw-footprints:R_0402_1005Metric")
    )
    (path ""
      (reference "R140") (unit 1) (value "R_20k_0402") (footprint "sa800u-baseboard-hw-footprints:R_0402_1005Metric")
    )
    (path ""
      (reference "R141") (unit 1) (value "R_52k3_0402") (footprint "sa800u-baseboard-hw-footprints:R_0402_1005Metric")
    )
    (path ""
      (reference "R142") (unit 1) (value "R_10k_0402") (footprint "sa800u-baseboard-hw-footprints:R_0402_1005Metric")
    )
    (path ""
      (reference "R143") (unit 1) (value "R_24k9_0402") (footprint "sa800u-baseboard-hw-footprints:R_0402_1005Metric")
    )
    (path ""
      (reference "R144") (unit 1) (value "R_63R4_0402") (footprint "sa800u-baseboard-hw-footprints:R_0402_1005Metric")
    )
    (path ""
      (reference "R145") (unit 1) (value "R_0R_0402") (footprint "sa800u-baseboard-hw-footprints:R_0402_1005Metric")
    )
    (path ""
      (reference "R146") (unit 1) (value "R_0R_0402") (footprint "sa800u-baseboard-hw-footprints:R_0402_1005Metric")
    )
    (path ""
      (reference "R147") (unit 1) (value "R_100k_0402") (footprint "sa800u-baseboard-hw-footprints:R_0402_1005Metric")
    )
    (path ""
      (reference "R148") (unit 1) (value "R_100k_0402") (footprint "sa800u-baseboard-hw-footprints:R_0402_1005Metric")
    )
    (path ""
      (reference "R149") (unit 1) (value "R_20k_0603") (footprint "sa800u-baseboard-hw-footprints:R_0603_1608Metric")
    )
    (path ""
      (reference "R150") (unit 1) (value "R_10k_0603") (footprint "sa800u-baseboard-hw-footprints:R_0603_1608Metric")
    )
    (path ""
      (reference "R151") (unit 1) (value "R_0R_0402") (footprint "sa800u-baseboard-hw-footprints:R_0402_1005Metric")
    )
    (path ""
      (reference "R152") (unit 1) (value "R_0R_0402") (footprint "sa800u-baseboard-hw-footprints:R_0402_1005Metric")
    )
    (path ""
      (reference "R153") (unit 1) (value "R_10k_0402") (footprint "sa800u-baseboard-hw-footprints:R_0402_1005Metric")
    )
    (path ""
      (reference "R154") (unit 1) (value "R_100k_0402") (footprint "sa800u-baseboard-hw-footprints:R_0402_1005Metric")
    )
    (path ""
      (reference "R155") (unit 1) (value "R_100k_0402") (footprint "sa800u-baseboard-hw-footprints:R_0402_1005Metric")
    )
    (path ""
      (reference "R156") (unit 1) (value "R_100k_0402") (footprint "sa800u-baseboard-hw-footprints:R_0402_1005Metric")
    )
    (path ""
      (reference "R157") (unit 1) (value "R_100k_0402") (footprint "sa800u-baseboard-hw-footprints:R_0402_1005Metric")
    )
    (path ""
      (reference "R158") (unit 1) (value "R_470R_0402") (footprint "sa800u-baseboard-hw-footprints:R_0402_1005Metric")
    )
    (path ""
      (reference "R159") (unit 1) (value "R_1k_0402") (footprint "sa800u-baseboard-hw-footprints:R_0402_1005Metric")
    )
    (path ""
      (reference "R160") (unit 1) (value "R_100k_0402") (footprint "sa800u-baseboard-hw-footprints:R_0402_1005Metric")
    )
    (path ""
      (reference "R161") (unit 1) (value "R_22k_0402") (footprint "sa800u-baseboard-hw-footprints:R_0402_1005Metric")
    )
    (path ""
      (reference "R162") (unit 1) (value "R_0R_0402") (footprint "sa800u-baseboard-hw-footprints:R_0402_1005Metric")
    )
    (path ""
      (reference "R163") (unit 1) (value "R_0R_0402") (footprint "sa800u-baseboard-hw-footprints:R_0402_1005Metric")
    )
    (path ""
      (reference "R164") (unit 1) (value "R_0R_0402") (footprint "sa800u-baseboard-hw-footprints:R_0402_1005Metric")
    )
    (path ""
      (reference "R165") (unit 1) (value "R_0R_0402") (footprint "sa800u-baseboard-hw-footprints:R_0402_1005Metric")
    )
    (path ""
      (reference "R166") (unit 1) (value "R_100R_0402") (footprint "sa800u-baseboard-hw-footprints:R_0402_1005Metric")
    )
    (path ""
      (reference "R167") (unit 1) (value "R_4k7_0402") (footprint "sa800u-baseboard-hw-footprints:R_0402_1005Metric")
    )
    (path ""
      (reference "R168") (unit 1) (value "R_4k7_0402") (footprint "sa800u-baseboard-hw-footprints:R_0402_1005Metric")
    )
    (path ""
      (reference "R169") (unit 1) (value "R_1k1_0402") (footprint "sa800u-baseboard-hw-footprints:R_0402_1005Metric")
    )
    (path ""
      (reference "R170") (unit 1) (value "R_4k7_0402") (footprint "sa800u-baseboard-hw-footprints:R_0402_1005Metric")
    )
    (path ""
      (reference "R171") (unit 1) (value "R_510R_0402") (footprint "sa800u-baseboard-hw-footprints:R_0402_1005Metric")
    )
    (path ""
      (reference "R172") (unit 1) (value "R_4k7_0402") (footprint "sa800u-baseboard-hw-footprints:R_0402_1005Metric")
    )
    (path ""
      (reference "R173") (unit 1) (value "R_750R_0402") (footprint "sa800u-baseboard-hw-footprints:R_0402_1005Metric")
    )
    (path ""
      (reference "R174") (unit 1) (value "R_2k7_0402") (footprint "sa800u-baseboard-hw-footprints:R_0402_1005Metric")
    )
    (path ""
      (reference "R175") (unit 1) (value "R_10k_0402") (footprint "sa800u-baseboard-hw-footprints:R_0402_1005Metric")
    )
    (path ""
      (reference "R176") (unit 1) (value "R_0R_0402") (footprint "sa800u-baseboard-hw-footprints:R_0402_1005Metric")
    )
    (path ""
      (reference "R177") (unit 1) (value "R_0R_0402") (footprint "sa800u-baseboard-hw-footprints:R_0402_1005Metric")
    )
    (path ""
      (reference "R178") (unit 1) (value "R_0R_0402") (footprint "sa800u-baseboard-hw-footprints:R_0402_1005Metric")
    )
    (path ""
      (reference "R179") (unit 1) (value "R_0R_0402") (footprint "sa800u-baseboard-hw-footprints:R_0402_1005Metric")
    )
    (path ""
      (reference "S1") (unit 1) (value "SW_SPST_KMR211NGLFS") (footprint "sa800u-baseboard-hw-footprints:SW_SPST_4.2x2.8")
    )
    (path ""
      (reference "S2") (unit 1) (value "SW_SPST_KMR211NGLFS") (footprint "sa800u-baseboard-hw-footprints:SW_SPST_4.2x2.8")
    )
    (path ""
      (reference "S3") (unit 1) (value "SW_SPST_KMR211NGLFS") (footprint "sa800u-baseboard-hw-footprints:SW_SPST_4.2x2.8")
    )
    (path ""
      (reference "S4") (unit 1) (value "SW_SPST_KMR211NGLFS") (footprint "sa800u-baseboard-hw-footprints:SW_SPST_4.2x2.8")
    )
    (path ""
      (reference "SP1") (unit 1) (value "Spacer_H6mm_9774060151") (footprint "sa800u-baseboard-hw-footprints:Spacer_SMD_M2.5_H6mm_Wurth_9774060151")
    )
    (path ""
      (reference "SP2") (unit 1) (value "Spacer_H6mm_9774060151") (footprint "sa800u-baseboard-hw-footprints:Spacer_SMD_M2.5_H6mm_Wurth_9774060151")
    )
    (path ""
      (reference "SP3") (unit 1) (value "Spacer_H6mm_9774060151") (footprint "sa800u-baseboard-hw-footprints:Spacer_SMD_M2.5_H6mm_Wurth_9774060151")
    )
    (path ""
      (reference "SP4") (unit 1) (value "Spacer_H6mm_9774060151") (footprint "sa800u-baseboard-hw-footprints:Spacer_SMD_M2.5_H6mm_Wurth_9774060151")
    )
    (path ""
      (reference "SP5") (unit 1) (value "Spacer_H4.0mm_9774040151") (footprint "sa800u-baseboard-hw-footprints:Spacer_SMD_M2.5_H4mm_Wurth_9774040151")
    )
    (path ""
      (reference "SW1") (unit 1) (value "SW_CVS-02B") (footprint "sa800u-baseboard-hw-footprints:SW_DIP_SPSTx02_Slide_Copal_CVS-02xB_W5.9mm_P1mm")
    )
    (path ""
      (reference "TP1") (unit 1) (value "TP_0.75mm_SMD") (footprint "sa800u-baseboard-hw-footprints:TP_SMD_0.75mm")
    )
    (path ""
      (reference "TP2") (unit 1) (value "TP_0.75mm_SMD") (footprint "sa800u-baseboard-hw-footprints:TP_SMD_0.75mm")
    )
    (path ""
      (reference "TP3") (unit 1) (value "TP_0.75mm_SMD") (footprint "sa800u-baseboard-hw-footprints:TP_SMD_0.75mm")
    )
    (path ""
      (reference "TP4") (unit 1) (value "TP_0.75mm_SMD") (footprint "sa800u-baseboard-hw-footprints:TP_SMD_0.75mm")
    )
    (path ""
      (reference "TP5") (unit 1) (value "TP_0.75mm_SMD") (footprint "sa800u-baseboard-hw-footprints:TP_SMD_0.75mm")
    )
    (path ""
      (reference "TP6") (unit 1) (value "TP_0.75mm_SMD") (footprint "sa800u-baseboard-hw-footprints:TP_SMD_0.75mm")
    )
    (path ""
      (reference "TP7") (unit 1) (value "TP_0.75mm_SMD") (footprint "sa800u-baseboard-hw-footprints:TP_SMD_0.75mm")
    )
    (path ""
      (reference "TP8") (unit 1) (value "TP_0.75mm_SMD") (footprint "sa800u-baseboard-hw-footprints:TP_SMD_0.75mm")
    )
    (path ""
      (reference "TP9") (unit 1) (value "TP_0.75mm_SMD") (footprint "sa800u-baseboard-hw-footprints:TP_SMD_0.75mm")
    )
    (path ""
      (reference "TP10") (unit 1) (value "TP_0.75mm_SMD") (footprint "sa800u-baseboard-hw-footprints:TP_SMD_0.75mm")
    )
    (path ""
      (reference "TP11") (unit 1) (value "TP_0.75mm_SMD") (footprint "sa800u-baseboard-hw-footprints:TP_SMD_0.75mm")
    )
    (path ""
      (reference "TP12") (unit 1) (value "TP_0.75mm_SMD") (footprint "sa800u-baseboard-hw-footprints:TP_SMD_0.75mm")
    )
    (path ""
      (reference "TP13") (unit 1) (value "TP_0.75mm_SMD") (footprint "sa800u-baseboard-hw-footprints:TP_SMD_0.75mm")
    )
    (path ""
      (reference "TP14") (unit 1) (value "TP_0.75mm_SMD") (footprint "sa800u-baseboard-hw-footprints:TP_SMD_0.75mm")
    )
    (path ""
      (reference "TP15") (unit 1) (value "TP_0.75mm_SMD") (footprint "sa800u-baseboard-hw-footprints:TP_SMD_0.75mm")
    )
    (path ""
      (reference "TP16") (unit 1) (value "TP_0.75mm_SMD") (footprint "sa800u-baseboard-hw-footprints:TP_SMD_0.75mm")
    )
    (path ""
      (reference "TP17") (unit 1) (value "TP_0.75mm_SMD") (footprint "sa800u-baseboard-hw-footprints:TP_SMD_0.75mm")
    )
    (path ""
      (reference "TP18") (unit 1) (value "TP_0.75mm_SMD") (footprint "sa800u-baseboard-hw-footprints:TP_SMD_0.75mm")
    )
    (path ""
      (reference "TP19") (unit 1) (value "TP_0.75mm_SMD") (footprint "sa800u-baseboard-hw-footprints:TP_SMD_0.75mm")
    )
    (path ""
      (reference "TP20") (unit 1) (value "TP_0.75mm_SMD") (footprint "sa800u-baseboard-hw-footprints:TP_SMD_0.75mm")
    )
    (path ""
      (reference "TP21") (unit 1) (value "TP_0.75mm_SMD") (footprint "sa800u-baseboard-hw-footprints:TP_SMD_0.75mm")
    )
    (path ""
      (reference "TP22") (unit 1) (value "TP_0.75mm_SMD") (footprint "sa800u-baseboard-hw-footprints:TP_SMD_0.75mm")
    )
    (path ""
      (reference "TP23") (unit 1) (value "TP_0.75mm_SMD") (footprint "sa800u-baseboard-hw-footprints:TP_SMD_0.75mm")
    )
    (path ""
      (reference "TP24") (unit 1) (value "TP_0.75mm_SMD") (footprint "sa800u-baseboard-hw-footprints:TP_SMD_0.75mm")
    )
    (path ""
      (reference "TP25") (unit 1) (value "TP_0.75mm_SMD") (footprint "sa800u-baseboard-hw-footprints:TP_SMD_0.75mm")
    )
    (path ""
      (reference "TP26") (unit 1) (value "TP_0.75mm_SMD") (footprint "sa800u-baseboard-hw-footprints:TP_SMD_0.75mm")
    )
    (path ""
      (reference "TP27") (unit 1) (value "TP_0.75mm_SMD") (footprint "sa800u-baseboard-hw-footprints:TP_SMD_0.75mm")
    )
    (path ""
      (reference "TP28") (unit 1) (value "TP_0.75mm_SMD") (footprint "sa800u-baseboard-hw-footprints:TP_SMD_0.75mm")
    )
    (path ""
      (reference "TP29") (unit 1) (value "TP_0.75mm_SMD") (footprint "sa800u-baseboard-hw-footprints:TP_SMD_0.75mm")
    )
    (path ""
      (reference "TP30") (unit 1) (value "TP_0.75mm_SMD") (footprint "sa800u-baseboard-hw-footprints:TP_SMD_0.75mm")
    )
    (path ""
      (reference "TP31") (unit 1) (value "TP_0.75mm_SMD") (footprint "sa800u-baseboard-hw-footprints:TP_SMD_0.75mm")
    )
    (path ""
      (reference "TP32") (unit 1) (value "TP_0.75mm_SMD") (footprint "sa800u-baseboard-hw-footprints:TP_SMD_0.75mm")
    )
    (path ""
      (reference "TP33") (unit 1) (value "TP_0.75mm_SMD") (footprint "sa800u-baseboard-hw-footprints:TP_SMD_0.75mm")
    )
    (path ""
      (reference "TP34") (unit 1) (value "TP_0.75mm_SMD") (footprint "sa800u-baseboard-hw-footprints:TP_SMD_0.75mm")
    )
    (path ""
      (reference "TP35") (unit 1) (value "TP_0.75mm_SMD") (footprint "sa800u-baseboard-hw-footprints:TP_SMD_0.75mm")
    )
    (path ""
      (reference "TP36") (unit 1) (value "TP_0.75mm_SMD") (footprint "sa800u-baseboard-hw-footprints:TP_SMD_0.75mm")
    )
    (path ""
      (reference "TP37") (unit 1) (value "TP_0.75mm_SMD") (footprint "sa800u-baseboard-hw-footprints:TP_SMD_0.75mm")
    )
    (path ""
      (reference "TP38") (unit 1) (value "TP_0.75mm_SMD") (footprint "sa800u-baseboard-hw-footprints:TP_SMD_0.75mm")
    )
    (path ""
      (reference "TP39") (unit 1) (value "TP_0.75mm_SMD") (footprint "sa800u-baseboard-hw-footprints:TP_SMD_0.75mm")
    )
    (path ""
      (reference "TP40") (unit 1) (value "TP_0.75mm_SMD") (footprint "sa800u-baseboard-hw-footprints:TP_SMD_0.75mm")
    )
    (path ""
      (reference "TP41") (unit 1) (value "TP_0.75mm_SMD") (footprint "sa800u-baseboard-hw-footprints:TP_SMD_0.75mm")
    )
    (path ""
      (reference "TP42") (unit 1) (value "TP_0.75mm_SMD") (footprint "sa800u-baseboard-hw-footprints:TP_SMD_0.75mm")
    )
    (path ""
      (reference "TP43") (unit 1) (value "TP_0.75mm_SMD") (footprint "sa800u-baseboard-hw-footprints:TP_SMD_0.75mm")
    )
    (path ""
      (reference "TP44") (unit 1) (value "TP_0.75mm_SMD") (footprint "sa800u-baseboard-hw-footprints:TP_SMD_0.75mm")
    )
    (path ""
      (reference "TP45") (unit 1) (value "TP_0.75mm_SMD") (footprint "sa800u-baseboard-hw-footprints:TP_SMD_0.75mm")
    )
    (path ""
      (reference "TP46") (unit 1) (value "TP_0.75mm_SMD") (footprint "sa800u-baseboard-hw-footprints:TP_SMD_0.75mm")
    )
    (path ""
      (reference "TP47") (unit 1) (value "TP_0.75mm_SMD") (footprint "sa800u-baseboard-hw-footprints:TP_SMD_0.75mm")
    )
    (path ""
      (reference "TP48") (unit 1) (value "TP_0.75mm_SMD") (footprint "sa800u-baseboard-hw-footprints:TP_SMD_0.75mm")
    )
    (path ""
      (reference "TP49") (unit 1) (value "TP_0.75mm_SMD") (footprint "sa800u-baseboard-hw-footprints:TP_SMD_0.75mm")
    )
    (path ""
      (reference "TP50") (unit 1) (value "TP_0.75mm_SMD") (footprint "sa800u-baseboard-hw-footprints:TP_SMD_0.75mm")
    )
    (path ""
      (reference "TP51") (unit 1) (value "TP_0.75mm_SMD") (footprint "sa800u-baseboard-hw-footprints:TP_SMD_0.75mm")
    )
    (path ""
      (reference "TP52") (unit 1) (value "TP_0.75mm_SMD") (footprint "sa800u-baseboard-hw-footprints:TP_SMD_0.75mm")
    )
    (path ""
      (reference "TP53") (unit 1) (value "TP_0.75mm_SMD") (footprint "sa800u-baseboard-hw-footprints:TP_SMD_0.75mm")
    )
    (path ""
      (reference "TP54") (unit 1) (value "TP_0.75mm_SMD") (footprint "sa800u-baseboard-hw-footprints:TP_SMD_0.75mm")
    )
    (path ""
      (reference "TP55") (unit 1) (value "TP_0.75mm_SMD") (footprint "sa800u-baseboard-hw-footprints:TP_SMD_0.75mm")
    )
    (path ""
      (reference "TP56") (unit 1) (value "TP_0.75mm_SMD") (footprint "sa800u-baseboard-hw-footprints:TP_SMD_0.75mm")
    )
    (path ""
      (reference "TP57") (unit 1) (value "TP_0.75mm_SMD") (footprint "sa800u-baseboard-hw-footprints:TP_SMD_0.75mm")
    )
    (path ""
      (reference "TP58") (unit 1) (value "TP_0.75mm_SMD") (footprint "sa800u-baseboard-hw-footprints:TP_SMD_0.75mm")
    )
    (path ""
      (reference "TP59") (unit 1) (value "TP_0.75mm_SMD") (footprint "sa800u-baseboard-hw-footprints:TP_SMD_0.75mm")
    )
    (path ""
      (reference "TP60") (unit 1) (value "TP_0.75mm_SMD") (footprint "sa800u-baseboard-hw-footprints:TP_SMD_0.75mm")
    )
    (path ""
      (reference "TP61") (unit 1) (value "TP_0.75mm_SMD") (footprint "sa800u-baseboard-hw-footprints:TP_SMD_0.75mm")
    )
    (path ""
      (reference "TP62") (unit 1) (value "TP_0.75mm_SMD") (footprint "sa800u-baseboard-hw-footprints:TP_SMD_0.75mm")
    )
    (path ""
      (reference "TP63") (unit 1) (value "TP_0.75mm_SMD") (footprint "sa800u-baseboard-hw-footprints:TP_SMD_0.75mm")
    )
    (path ""
      (reference "TP64") (unit 1) (value "TP_0.75mm_SMD") (footprint "sa800u-baseboard-hw-footprints:TP_SMD_0.75mm")
    )
    (path ""
      (reference "TP65") (unit 1) (value "TP_0.75mm_SMD") (footprint "sa800u-baseboard-hw-footprints:TP_SMD_0.75mm")
    )
    (path ""
      (reference "TP66") (unit 1) (value "TP_0.75mm_SMD") (footprint "sa800u-baseboard-hw-footprints:TP_SMD_0.75mm")
    )
    (path ""
      (reference "TP67") (unit 1) (value "TP_0.75mm_SMD") (footprint "sa800u-baseboard-hw-footprints:TP_SMD_0.75mm")
    )
    (path ""
      (reference "TP68") (unit 1) (value "TP_0.75mm_SMD") (footprint "sa800u-baseboard-hw-footprints:TP_SMD_0.75mm")
    )
    (path ""
      (reference "TP69") (unit 1) (value "TP_0.75mm_SMD") (footprint "sa800u-baseboard-hw-footprints:TP_SMD_0.75mm")
    )
    (path ""
      (reference "TP70") (unit 1) (value "TP_0.75mm_SMD") (footprint "sa800u-baseboard-hw-footprints:TP_SMD_0.75mm")
    )
    (path ""
      (reference "TP71") (unit 1) (value "TP_0.75mm_SMD") (footprint "sa800u-baseboard-hw-footprints:TP_SMD_0.75mm")
    )
    (path ""
      (reference "TP72") (unit 1) (value "TP_0.75mm_SMD") (footprint "sa800u-baseboard-hw-footprints:TP_SMD_0.75mm")
    )
    (path ""
      (reference "TP73") (unit 1) (value "TP_0.75mm_SMD") (footprint "sa800u-baseboard-hw-footprints:TP_SMD_0.75mm")
    )
    (path ""
      (reference "TP74") (unit 1) (value "TP_0.75mm_SMD") (footprint "sa800u-baseboard-hw-footprints:TP_SMD_0.75mm")
    )
    (path ""
      (reference "TP75") (unit 1) (value "TP_0.75mm_SMD") (footprint "sa800u-baseboard-hw-footprints:TP_SMD_0.75mm")
    )
    (path ""
      (reference "TP76") (unit 1) (value "TP_0.75mm_SMD") (footprint "sa800u-baseboard-hw-footprints:TP_SMD_0.75mm")
    )
    (path ""
      (reference "TP77") (unit 1) (value "TP_0.75mm_SMD") (footprint "sa800u-baseboard-hw-footprints:TP_SMD_0.75mm")
    )
    (path ""
      (reference "TP78") (unit 1) (value "TP_0.75mm_SMD") (footprint "sa800u-baseboard-hw-footprints:TP_SMD_0.75mm")
    )
    (path ""
      (reference "TP79") (unit 1) (value "TP_0.75mm_SMD") (footprint "sa800u-baseboard-hw-footprints:TP_SMD_0.75mm")
    )
    (path ""
      (reference "TP80") (unit 1) (value "TP_0.75mm_SMD") (footprint "sa800u-baseboard-hw-footprints:TP_SMD_0.75mm")
    )
    (path ""
      (reference "TP81") (unit 1) (value "TP_0.75mm_SMD") (footprint "sa800u-baseboard-hw-footprints:TP_SMD_0.75mm")
    )
    (path ""
      (reference "TP82") (unit 1) (value "TP_0.75mm_SMD") (footprint "sa800u-baseboard-hw-footprints:TP_SMD_0.75mm")
    )
    (path ""
      (reference "TP83") (unit 1) (value "TP_0.75mm_SMD") (footprint "sa800u-baseboard-hw-footprints:TP_SMD_0.75mm")
    )
    (path ""
      (reference "TP84") (unit 1) (value "TP_0.75mm_SMD") (footprint "sa800u-baseboard-hw-footprints:TP_SMD_0.75mm")
    )
    (path ""
      (reference "TP85") (unit 1) (value "TP_0.75mm_SMD") (footprint "sa800u-baseboard-hw-footprints:TP_SMD_0.75mm")
    )
    (path ""
      (reference "TP86") (unit 1) (value "TP_0.75mm_SMD") (footprint "sa800u-baseboard-hw-footprints:TP_SMD_0.75mm")
    )
    (path ""
      (reference "TP87") (unit 1) (value "TP_0.75mm_SMD") (footprint "sa800u-baseboard-hw-footprints:TP_SMD_0.75mm")
    )
    (path ""
      (reference "TP88") (unit 1) (value "TP_0.75mm_SMD") (footprint "sa800u-baseboard-hw-footprints:TP_SMD_0.75mm")
    )
    (path ""
      (reference "TP89") (unit 1) (value "TP_0.75mm_SMD") (footprint "sa800u-baseboard-hw-footprints:TP_SMD_0.75mm")
    )
    (path ""
      (reference "TP90") (unit 1) (value "TP_0.75mm_SMD") (footprint "sa800u-baseboard-hw-footprints:TP_SMD_0.75mm")
    )
    (path ""
      (reference "TP91") (unit 1) (value "TP_0.75mm_SMD") (footprint "sa800u-baseboard-hw-footprints:TP_SMD_0.75mm")
    )
    (path ""
      (reference "TP92") (unit 1) (value "TP_0.75mm_SMD") (footprint "sa800u-baseboard-hw-footprints:TP_SMD_0.75mm")
    )
    (path ""
      (reference "TP93") (unit 1) (value "TP_0.75mm_SMD") (footprint "sa800u-baseboard-hw-footprints:TP_SMD_0.75mm")
    )
    (path ""
      (reference "TP94") (unit 1) (value "TP_0.75mm_SMD") (footprint "sa800u-baseboard-hw-footprints:TP_SMD_0.75mm")
    )
    (path ""
      (reference "TP95") (unit 1) (value "TP_0.75mm_SMD") (footprint "sa800u-baseboard-hw-footprints:TP_SMD_0.75mm")
    )
    (path ""
      (reference "TP96") (unit 1) (value "TP_0.75mm_SMD") (footprint "sa800u-baseboard-hw-footprints:TP_SMD_0.75mm")
    )
    (path ""
      (reference "TP97") (unit 1) (value "TP_0.75mm_SMD") (footprint "sa800u-baseboard-hw-footprints:TP_SMD_0.75mm")
    )
    (path ""
      (reference "TP98") (unit 1) (value "TP_0.75mm_SMD") (footprint "sa800u-baseboard-hw-footprints:TP_SMD_0.75mm")
    )
    (path ""
      (reference "TP99") (unit 1) (value "TP_0.75mm_SMD") (footprint "sa800u-baseboard-hw-footprints:TP_SMD_0.75mm")
    )
    (path ""
      (reference "TP100") (unit 1) (value "TP_0.75mm_SMD") (footprint "sa800u-baseboard-hw-footprints:TP_SMD_0.75mm")
    )
    (path ""
      (reference "TP101") (unit 1) (value "TP_0.75mm_SMD") (footprint "sa800u-baseboard-hw-footprints:TP_SMD_0.75mm")
    )
    (path ""
      (reference "TP102") (unit 1) (value "TP_0.75mm_SMD") (footprint "sa800u-baseboard-hw-footprints:TP_SMD_0.75mm")
    )
    (path ""
      (reference "TP103") (unit 1) (value "TP_0.75mm_SMD") (footprint "sa800u-baseboard-hw-footprints:TP_SMD_0.75mm")
    )
    (path ""
      (reference "TP104") (unit 1) (value "TP_0.75mm_SMD") (footprint "sa800u-baseboard-hw-footprints:TP_SMD_0.75mm")
    )
    (path ""
      (reference "TP105") (unit 1) (value "TP_0.75mm_SMD") (footprint "sa800u-baseboard-hw-footprints:TP_SMD_0.75mm")
    )
    (path ""
      (reference "TP106") (unit 1) (value "TP_0.75mm_SMD") (footprint "sa800u-baseboard-hw-footprints:TP_SMD_0.75mm")
    )
    (path ""
      (reference "TP107") (unit 1) (value "TP_0.75mm_SMD") (footprint "sa800u-baseboard-hw-footprints:TP_SMD_0.75mm")
    )
    (path ""
      (reference "TP108") (unit 1) (value "TP_0.75mm_SMD") (footprint "sa800u-baseboard-hw-footprints:TP_SMD_0.75mm")
    )
    (path ""
      (reference "TP109") (unit 1) (value "TP_0.75mm_SMD") (footprint "sa800u-baseboard-hw-footprints:TP_SMD_0.75mm")
    )
    (path ""
      (reference "TP110") (unit 1) (value "TP_0.75mm_SMD") (footprint "sa800u-baseboard-hw-footprints:TP_SMD_0.75mm")
    )
    (path ""
      (reference "TP111") (unit 1) (value "TP_0.75mm_SMD") (footprint "sa800u-baseboard-hw-footprints:TP_SMD_0.75mm")
    )
    (path ""
      (reference "TP112") (unit 1) (value "TP_0.75mm_SMD") (footprint "sa800u-baseboard-hw-footprints:TP_SMD_0.75mm")
    )
    (path ""
      (reference "U1") (unit 1) (value "RTL8111H") (footprint "sa800u-baseboard-hw-footprints:QFN-32-1EP_4x4mm_P0.4mm")
    )
    (path ""
      (reference "U2") (unit 1) (value "TXB0104_UQFN") (footprint "sa800u-baseboard-hw-footprints:UQFN-12_2x1.7mm_P0.4mm_Texas_RUT")
    )
    (path ""
      (reference "U3") (unit 1) (value "LT9611") (footprint "sa800u-baseboard-hw-footprints:QFN-64-1EP_7.5x7.5mm_P0.4mm")
    )
    (path ""
      (reference "U4") (unit 1) (value "NTS0102_XSON") (footprint "sa800u-baseboard-hw-footprints:XSON-8_1x1.95mm_P0.5mm")
    )
    (path ""
      (reference "U5") (unit 1) (value "FT232R_QFN") (footprint "sa800u-baseboard-hw-footprints:QFN-32-1EP_5x5mm")
    )
    (path ""
      (reference "U6") (unit 1) (value "TPS25820DSST") (footprint "sa800u-baseboard-hw-footprints:WSON-12-1EP_2x3mm_P0.5mm")
    )
    (path ""
      (reference "U7") (unit 1) (value "NX3DV42GU") (footprint "sa800u-baseboard-hw-footprints:XQFN-10-1.4x1.8mm_P0.4mm")
    )
    (path ""
      (reference "U8") (unit 1) (value "TXB0104_UQFN") (footprint "sa800u-baseboard-hw-footprints:UQFN-12_2x1.7mm_P0.4mm_Texas_RUT")
    )
    (path ""
      (reference "U9") (unit 1) (value "CBTL02043ABQ,115") (footprint "sa800u-baseboard-hw-footprints:DHVQFN-20-1EP_2.5x4.5_P0.5mm")
    )
    (path ""
      (reference "U10") (unit 1) (value "NTS0102_XSON") (footprint "sa800u-baseboard-hw-footprints:XSON-8_1x1.95mm_P0.5mm")
    )
    (path ""
      (reference "U11") (unit 1) (value "Receptacle_SA800U-WF") (footprint "sa800u-baseboard-hw-footprints:Receptacle_SA800U-WF")
    )
    (path ""
      (reference "U11") (unit 2) (value "Receptacle_SA800U-WF") (footprint "sa800u-baseboard-hw-footprints:Receptacle_SA800U-WF")
    )
    (path ""
      (reference "U12") (unit 1) (value "AP2114H-3.3TRG1") (footprint "sa800u-baseboard-hw-footprints:SOT-223")
    )
    (path ""
      (reference "U13") (unit 1) (value "NTS0102_XSON") (footprint "sa800u-baseboard-hw-footprints:XSON-8_1x1.95mm_P0.5mm")
    )
    (path ""
      (reference "U14") (unit 1) (value "NTS0102_XSON") (footprint "sa800u-baseboard-hw-footprints:XSON-8_1x1.95mm_P0.5mm")
    )
    (path ""
      (reference "U15") (unit 1) (value "Bus_M.2_MDT580M01001") (footprint "sa800u-baseboard-hw-footprints:Bus_M.2_Socket_Key_M_Amphenol_MDT580M01001")
    )
    (path ""
      (reference "U16") (unit 1) (value "NTS0102_XSON") (footprint "sa800u-baseboard-hw-footprints:XSON-8_1x1.95mm_P0.5mm")
    )
    (path ""
      (reference "U17") (unit 1) (value "LTC4417_QFN") (footprint "sa800u-baseboard-hw-footprints:QFN-24-1EP_4x4mm_EP2.1x2.1mm")
    )
    (path ""
      (reference "U18") (unit 1) (value "LMV431_SOT-23-5") (footprint "sa800u-baseboard-hw-footprints:SOT-23-5")
    )
    (path ""
      (reference "U19") (unit 1) (value "AP62301WU-7") (footprint "sa800u-baseboard-hw-footprints:AP62301WU-7-TSOT23-6")
    )
    (path ""
      (reference "U20") (unit 1) (value "AP62301WU-7") (footprint "sa800u-baseboard-hw-footprints:AP62301WU-7-TSOT23-6")
    )
    (path ""
      (reference "U21") (unit 1) (value "AP62301WU-7") (footprint "sa800u-baseboard-hw-footprints:AP62301WU-7-TSOT23-6")
    )
    (path ""
      (reference "U22") (unit 1) (value "AP62301WU-7") (footprint "sa800u-baseboard-hw-footprints:AP62301WU-7-TSOT23-6")
    )
    (path ""
      (reference "U23") (unit 1) (value "STUSB4500_QFN") (footprint "sa800u-baseboard-hw-footprints:QFN-24-1EP_4x4mm_EP2.1x2.1mm")
    )
    (path ""
      (reference "Y1") (unit 1) (value "Oscillator_SMD_25MHz_KX-7") (footprint "sa800u-baseboard-hw-footprints:Oscillator_SMD_Geyer_KX-7-4Pin_3.2x2.5mm")
    )
    (path ""
      (reference "Y2") (unit 1) (value "ABM8G-24.000MHZ-18-D2Y-T") (footprint "sa800u-baseboard-hw-footprints:Oscillator_SMD_Geyer_KX-7-4Pin_3.2x2.5mm")
    )
  )
)
